FILE_TYPE = MACRO_DRAWING;
SET COLOR_WIRE YELLOW;
SET COLOR_PROP MONO;
SET COLOR_DOT WHITE;
SET COLOR_ARC YELLOW;
SET COLOR_BODY GREEN;
SET COLOR_NOTE MONO;
SET PROP_DISPLAY VALUE;
SET PAGE_NUMBER P62;
FORCEADD OFFPAGE..5
(-6450 500);
FORCEPROP 2 LAST $XR1 88 
J 0
(-6764 500);
DISPLAY 0.638298 (-6764 500);
PAINT MONO (-6764 500);
FORCEPROP 2 LAST $XR0 87 
J 0
(-6674 500);
DISPLAY 0.638298 (-6674 500);
PAINT MONO (-6674 500);
FORCEPROP 2 LAST PATH I1
J 0
(-6400 575);
DISPLAY 1.021277 (-6400 575);
PAINT ORANGE (-6400 575);
DISPLAY INVISIBLE (-6400 575);
FORCEPROP 1 LAST COMMENT_BODY TRUE
J 0
(-6350 425);
DISPLAY 1.170213 (-6350 425);
PAINT GREEN (-6350 425);
DISPLAY INVISIBLE (-6350 425);
FORCEPROP 1 LAST OFFPAGE TRUE
J 0
(-6125 375);
DISPLAY 1.170213 (-6125 375);
PAINT GREEN (-6125 375);
DISPLAY INVISIBLE (-6125 375);
FORCEPROP 2 LAST CDS_LIB mstr_standard
J 0
(-6450 500);
PAINT MONO (-6450 500);
DISPLAY INVISIBLE (-6450 500);
FORCEADD TAP..6
(-5600 800);
FORCEPROP 3 LASTPIN (-5550 800) SIG_NAME M_M_CLK_DP<0>
J 0
(-5540 810);
DISPLAY 0.659574 (-5540 810);
PAINT MONO (-5540 810);
DISPLAY INVISIBLE (-5540 810);
FORCEPROP 1 LASTPIN (-5550 800) BN 0
J 0
(-5602 808);
DISPLAY 0.617021 (-5602 808);
PAINT GREEN (-5602 808);
FORCEPROP 1 LAST PATH I10
J 0
(-5602 800);
DISPLAY 0.872340 (-5602 800);
PAINT GREEN (-5602 800);
DISPLAY INVISIBLE (-5602 800);
FORCEPROP 1 LAST HDL_TAP TRUE
J 0
(-5275 675);
DISPLAY 1.595745 (-5275 675);
PAINT GREEN (-5275 675);
DISPLAY INVISIBLE (-5275 675);
FORCEPROP 1 LAST BODY_TYPE PLUMBING
J 0
(-5600 750);
DISPLAY 1.595745 (-5600 750);
PAINT GREEN (-5600 750);
DISPLAY INVISIBLE (-5600 750);
FORCEPROP 2 LAST CDS_LIB mstr_standard
J 0
(-5600 800);
PAINT MONO (-5600 800);
DISPLAY INVISIBLE (-5600 800);
FORCEADD TAP..6
R 2
(-2875 1550);
FORCEPROP 3 LASTPIN (-2925 1550) SIG_NAME M_M_ODT<3>
J 0
(-2915 1560);
DISPLAY 0.659574 (-2915 1560);
PAINT MONO (-2915 1560);
DISPLAY INVISIBLE (-2915 1560);
FORCEPROP 1 LASTPIN (-2925 1550) BN 3
J 2
(-2873 1558);
DISPLAY 0.617021 (-2873 1558);
PAINT GREEN (-2873 1558);
FORCEPROP 1 LAST PATH I100
J 2
(-2873 1550);
DISPLAY 0.872340 (-2873 1550);
PAINT GREEN (-2873 1550);
DISPLAY INVISIBLE (-2873 1550);
FORCEPROP 1 LAST HDL_TAP TRUE
J 2
(-3200 1425);
DISPLAY 1.595745 (-3200 1425);
PAINT GREEN (-3200 1425);
DISPLAY INVISIBLE (-3200 1425);
FORCEPROP 1 LAST BODY_TYPE PLUMBING
J 2
(-2875 1500);
DISPLAY 1.595745 (-2875 1500);
PAINT GREEN (-2875 1500);
DISPLAY INVISIBLE (-2875 1500);
FORCEPROP 2 LAST CDS_LIB mstr_standard
J 0
(-2875 1550);
PAINT MONO (-2875 1550);
DISPLAY INVISIBLE (-2875 1550);
FORCEADD TAP..6
R 2
(-2875 1500);
FORCEPROP 3 LASTPIN (-2925 1500) SIG_NAME M_M_ODT<2>
J 0
(-2915 1510);
DISPLAY 0.659574 (-2915 1510);
PAINT MONO (-2915 1510);
DISPLAY INVISIBLE (-2915 1510);
FORCEPROP 1 LASTPIN (-2925 1500) BN 2
J 2
(-2873 1508);
DISPLAY 0.617021 (-2873 1508);
PAINT GREEN (-2873 1508);
FORCEPROP 1 LAST PATH I101
J 2
(-2873 1500);
DISPLAY 0.872340 (-2873 1500);
PAINT GREEN (-2873 1500);
DISPLAY INVISIBLE (-2873 1500);
FORCEPROP 1 LAST HDL_TAP TRUE
J 2
(-3200 1375);
DISPLAY 1.595745 (-3200 1375);
PAINT GREEN (-3200 1375);
DISPLAY INVISIBLE (-3200 1375);
FORCEPROP 1 LAST BODY_TYPE PLUMBING
J 2
(-2875 1450);
DISPLAY 1.595745 (-2875 1450);
PAINT GREEN (-2875 1450);
DISPLAY INVISIBLE (-2875 1450);
FORCEPROP 2 LAST CDS_LIB mstr_standard
J 0
(-2875 1500);
PAINT MONO (-2875 1500);
DISPLAY INVISIBLE (-2875 1500);
FORCEADD TAP..6
R 2
(-2875 1450);
FORCEPROP 3 LASTPIN (-2925 1450) SIG_NAME M_M_ODT<1>
J 0
(-2915 1460);
DISPLAY 0.659574 (-2915 1460);
PAINT MONO (-2915 1460);
DISPLAY INVISIBLE (-2915 1460);
FORCEPROP 1 LASTPIN (-2925 1450) BN 1
J 2
(-2873 1458);
DISPLAY 0.617021 (-2873 1458);
PAINT GREEN (-2873 1458);
FORCEPROP 1 LAST PATH I102
J 2
(-2873 1450);
DISPLAY 0.872340 (-2873 1450);
PAINT GREEN (-2873 1450);
DISPLAY INVISIBLE (-2873 1450);
FORCEPROP 1 LAST HDL_TAP TRUE
J 2
(-3200 1325);
DISPLAY 1.595745 (-3200 1325);
PAINT GREEN (-3200 1325);
DISPLAY INVISIBLE (-3200 1325);
FORCEPROP 1 LAST BODY_TYPE PLUMBING
J 2
(-2875 1400);
DISPLAY 1.595745 (-2875 1400);
PAINT GREEN (-2875 1400);
DISPLAY INVISIBLE (-2875 1400);
FORCEPROP 2 LAST CDS_LIB mstr_standard
J 0
(-2875 1450);
PAINT MONO (-2875 1450);
DISPLAY INVISIBLE (-2875 1450);
FORCEADD TAP..6
R 2
(-2875 1650);
FORCEPROP 3 LASTPIN (-2925 1650) SIG_NAME M_M_CKE<0>
J 0
(-2915 1660);
DISPLAY 0.659574 (-2915 1660);
PAINT MONO (-2915 1660);
DISPLAY INVISIBLE (-2915 1660);
FORCEPROP 1 LASTPIN (-2925 1650) BN 0
J 2
(-2873 1658);
DISPLAY 0.617021 (-2873 1658);
PAINT GREEN (-2873 1658);
FORCEPROP 1 LAST PATH I103
J 2
(-2873 1650);
DISPLAY 0.872340 (-2873 1650);
PAINT GREEN (-2873 1650);
DISPLAY INVISIBLE (-2873 1650);
FORCEPROP 1 LAST HDL_TAP TRUE
J 2
(-3200 1525);
DISPLAY 1.595745 (-3200 1525);
PAINT GREEN (-3200 1525);
DISPLAY INVISIBLE (-3200 1525);
FORCEPROP 1 LAST BODY_TYPE PLUMBING
J 2
(-2875 1600);
DISPLAY 1.595745 (-2875 1600);
PAINT GREEN (-2875 1600);
DISPLAY INVISIBLE (-2875 1600);
FORCEPROP 2 LAST CDS_LIB mstr_standard
J 0
(-2875 1650);
PAINT MONO (-2875 1650);
DISPLAY INVISIBLE (-2875 1650);
FORCEADD TAP..6
R 2
(-2875 1700);
FORCEPROP 3 LASTPIN (-2925 1700) SIG_NAME M_M_CKE<1>
J 0
(-2915 1710);
DISPLAY 0.659574 (-2915 1710);
PAINT MONO (-2915 1710);
DISPLAY INVISIBLE (-2915 1710);
FORCEPROP 1 LASTPIN (-2925 1700) BN 1
J 2
(-2873 1708);
DISPLAY 0.617021 (-2873 1708);
PAINT GREEN (-2873 1708);
FORCEPROP 1 LAST PATH I104
J 2
(-2873 1700);
DISPLAY 0.872340 (-2873 1700);
PAINT GREEN (-2873 1700);
DISPLAY INVISIBLE (-2873 1700);
FORCEPROP 1 LAST HDL_TAP TRUE
J 2
(-3200 1575);
DISPLAY 1.595745 (-3200 1575);
PAINT GREEN (-3200 1575);
DISPLAY INVISIBLE (-3200 1575);
FORCEPROP 1 LAST BODY_TYPE PLUMBING
J 2
(-2875 1650);
DISPLAY 1.595745 (-2875 1650);
PAINT GREEN (-2875 1650);
DISPLAY INVISIBLE (-2875 1650);
FORCEPROP 2 LAST CDS_LIB mstr_standard
J 0
(-2875 1700);
PAINT MONO (-2875 1700);
DISPLAY INVISIBLE (-2875 1700);
FORCEADD TAP..6
R 2
(-2875 1750);
FORCEPROP 3 LASTPIN (-2925 1750) SIG_NAME M_M_CKE<2>
J 0
(-2915 1760);
DISPLAY 0.659574 (-2915 1760);
PAINT MONO (-2915 1760);
DISPLAY INVISIBLE (-2915 1760);
FORCEPROP 1 LASTPIN (-2925 1750) BN 2
J 2
(-2873 1758);
DISPLAY 0.617021 (-2873 1758);
PAINT GREEN (-2873 1758);
FORCEPROP 1 LAST PATH I105
J 2
(-2873 1750);
DISPLAY 0.872340 (-2873 1750);
PAINT GREEN (-2873 1750);
DISPLAY INVISIBLE (-2873 1750);
FORCEPROP 1 LAST HDL_TAP TRUE
J 2
(-3200 1625);
DISPLAY 1.595745 (-3200 1625);
PAINT GREEN (-3200 1625);
DISPLAY INVISIBLE (-3200 1625);
FORCEPROP 1 LAST BODY_TYPE PLUMBING
J 2
(-2875 1700);
DISPLAY 1.595745 (-2875 1700);
PAINT GREEN (-2875 1700);
DISPLAY INVISIBLE (-2875 1700);
FORCEPROP 2 LAST CDS_LIB mstr_standard
J 0
(-2875 1750);
PAINT MONO (-2875 1750);
DISPLAY INVISIBLE (-2875 1750);
FORCEADD TAP..6
R 2
(-2875 1800);
FORCEPROP 3 LASTPIN (-2925 1800) SIG_NAME M_M_CKE<3>
J 0
(-2915 1810);
DISPLAY 0.659574 (-2915 1810);
PAINT MONO (-2915 1810);
DISPLAY INVISIBLE (-2915 1810);
FORCEPROP 1 LASTPIN (-2925 1800) BN 3
J 2
(-2873 1808);
DISPLAY 0.617021 (-2873 1808);
PAINT GREEN (-2873 1808);
FORCEPROP 1 LAST PATH I106
J 2
(-2873 1800);
DISPLAY 0.872340 (-2873 1800);
PAINT GREEN (-2873 1800);
DISPLAY INVISIBLE (-2873 1800);
FORCEPROP 1 LAST HDL_TAP TRUE
J 2
(-3200 1675);
DISPLAY 1.595745 (-3200 1675);
PAINT GREEN (-3200 1675);
DISPLAY INVISIBLE (-3200 1675);
FORCEPROP 1 LAST BODY_TYPE PLUMBING
J 2
(-2875 1750);
DISPLAY 1.595745 (-2875 1750);
PAINT GREEN (-2875 1750);
DISPLAY INVISIBLE (-2875 1750);
FORCEPROP 2 LAST CDS_LIB mstr_standard
J 0
(-2875 1800);
PAINT MONO (-2875 1800);
DISPLAY INVISIBLE (-2875 1800);
FORCEADD TAP..6
R 2
(-2875 1900);
FORCEPROP 3 LASTPIN (-2925 1900) SIG_NAME M_M_MA<0>
J 0
(-2915 1910);
DISPLAY 0.659574 (-2915 1910);
PAINT MONO (-2915 1910);
DISPLAY INVISIBLE (-2915 1910);
FORCEPROP 1 LASTPIN (-2925 1900) BN 0
J 2
(-2873 1908);
DISPLAY 0.617021 (-2873 1908);
PAINT GREEN (-2873 1908);
FORCEPROP 1 LAST PATH I107
J 2
(-2873 1900);
DISPLAY 0.872340 (-2873 1900);
PAINT GREEN (-2873 1900);
DISPLAY INVISIBLE (-2873 1900);
FORCEPROP 1 LAST HDL_TAP TRUE
J 2
(-3200 1775);
DISPLAY 1.595745 (-3200 1775);
PAINT GREEN (-3200 1775);
DISPLAY INVISIBLE (-3200 1775);
FORCEPROP 1 LAST BODY_TYPE PLUMBING
J 2
(-2875 1850);
DISPLAY 1.595745 (-2875 1850);
PAINT GREEN (-2875 1850);
DISPLAY INVISIBLE (-2875 1850);
FORCEPROP 2 LAST CDS_LIB mstr_standard
J 0
(-2875 1900);
PAINT MONO (-2875 1900);
DISPLAY INVISIBLE (-2875 1900);
FORCEADD TAP..6
R 2
(-2875 1950);
FORCEPROP 3 LASTPIN (-2925 1950) SIG_NAME M_M_MA<1>
J 0
(-2915 1960);
DISPLAY 0.659574 (-2915 1960);
PAINT MONO (-2915 1960);
DISPLAY INVISIBLE (-2915 1960);
FORCEPROP 1 LASTPIN (-2925 1950) BN 1
J 2
(-2873 1958);
DISPLAY 0.617021 (-2873 1958);
PAINT GREEN (-2873 1958);
FORCEPROP 1 LAST PATH I108
J 2
(-2873 1950);
DISPLAY 0.872340 (-2873 1950);
PAINT GREEN (-2873 1950);
DISPLAY INVISIBLE (-2873 1950);
FORCEPROP 1 LAST HDL_TAP TRUE
J 2
(-3200 1825);
DISPLAY 1.595745 (-3200 1825);
PAINT GREEN (-3200 1825);
DISPLAY INVISIBLE (-3200 1825);
FORCEPROP 1 LAST BODY_TYPE PLUMBING
J 2
(-2875 1900);
DISPLAY 1.595745 (-2875 1900);
PAINT GREEN (-2875 1900);
DISPLAY INVISIBLE (-2875 1900);
FORCEPROP 2 LAST CDS_LIB mstr_standard
J 0
(-2875 1950);
PAINT MONO (-2875 1950);
DISPLAY INVISIBLE (-2875 1950);
FORCEADD TAP..6
R 2
(-2875 2050);
FORCEPROP 3 LASTPIN (-2925 2050) SIG_NAME M_M_MA<3>
J 0
(-2915 2060);
DISPLAY 0.659574 (-2915 2060);
PAINT MONO (-2915 2060);
DISPLAY INVISIBLE (-2915 2060);
FORCEPROP 1 LASTPIN (-2925 2050) BN 3
J 2
(-2873 2058);
DISPLAY 0.617021 (-2873 2058);
PAINT GREEN (-2873 2058);
FORCEPROP 1 LAST PATH I109
J 2
(-2873 2050);
DISPLAY 0.872340 (-2873 2050);
PAINT GREEN (-2873 2050);
DISPLAY INVISIBLE (-2873 2050);
FORCEPROP 1 LAST HDL_TAP TRUE
J 2
(-3200 1925);
DISPLAY 1.595745 (-3200 1925);
PAINT GREEN (-3200 1925);
DISPLAY INVISIBLE (-3200 1925);
FORCEPROP 1 LAST BODY_TYPE PLUMBING
J 2
(-2875 2000);
DISPLAY 1.595745 (-2875 2000);
PAINT GREEN (-2875 2000);
DISPLAY INVISIBLE (-2875 2000);
FORCEPROP 2 LAST CDS_LIB mstr_standard
J 0
(-2875 2050);
PAINT MONO (-2875 2050);
DISPLAY INVISIBLE (-2875 2050);
FORCEADD TAP..6
(-5600 900);
FORCEPROP 3 LASTPIN (-5550 900) SIG_NAME M_M_CLK_DP<2>
J 0
(-5540 910);
DISPLAY 0.659574 (-5540 910);
PAINT MONO (-5540 910);
DISPLAY INVISIBLE (-5540 910);
FORCEPROP 1 LASTPIN (-5550 900) BN 2
J 0
(-5602 908);
DISPLAY 0.617021 (-5602 908);
PAINT GREEN (-5602 908);
FORCEPROP 1 LAST PATH I11
J 0
(-5602 900);
DISPLAY 0.872340 (-5602 900);
PAINT GREEN (-5602 900);
DISPLAY INVISIBLE (-5602 900);
FORCEPROP 1 LAST HDL_TAP TRUE
J 0
(-5275 775);
DISPLAY 1.595745 (-5275 775);
PAINT GREEN (-5275 775);
DISPLAY INVISIBLE (-5275 775);
FORCEPROP 1 LAST BODY_TYPE PLUMBING
J 0
(-5600 850);
DISPLAY 1.595745 (-5600 850);
PAINT GREEN (-5600 850);
DISPLAY INVISIBLE (-5600 850);
FORCEPROP 2 LAST CDS_LIB mstr_standard
J 0
(-5600 900);
PAINT MONO (-5600 900);
DISPLAY INVISIBLE (-5600 900);
FORCEADD TAP..6
R 2
(-2875 2000);
FORCEPROP 3 LASTPIN (-2925 2000) SIG_NAME M_M_MA<2>
J 0
(-2915 2010);
DISPLAY 0.659574 (-2915 2010);
PAINT MONO (-2915 2010);
DISPLAY INVISIBLE (-2915 2010);
FORCEPROP 1 LASTPIN (-2925 2000) BN 2
J 2
(-2873 2008);
DISPLAY 0.617021 (-2873 2008);
PAINT GREEN (-2873 2008);
FORCEPROP 1 LAST PATH I110
J 2
(-2873 2000);
DISPLAY 0.872340 (-2873 2000);
PAINT GREEN (-2873 2000);
DISPLAY INVISIBLE (-2873 2000);
FORCEPROP 1 LAST HDL_TAP TRUE
J 2
(-3200 1875);
DISPLAY 1.595745 (-3200 1875);
PAINT GREEN (-3200 1875);
DISPLAY INVISIBLE (-3200 1875);
FORCEPROP 1 LAST BODY_TYPE PLUMBING
J 2
(-2875 1950);
DISPLAY 1.595745 (-2875 1950);
PAINT GREEN (-2875 1950);
DISPLAY INVISIBLE (-2875 1950);
FORCEPROP 2 LAST CDS_LIB mstr_standard
J 0
(-2875 2000);
PAINT MONO (-2875 2000);
DISPLAY INVISIBLE (-2875 2000);
FORCEADD TAP..6
R 2
(-2875 2100);
FORCEPROP 3 LASTPIN (-2925 2100) SIG_NAME M_M_MA<4>
J 0
(-2915 2110);
DISPLAY 0.659574 (-2915 2110);
PAINT MONO (-2915 2110);
DISPLAY INVISIBLE (-2915 2110);
FORCEPROP 1 LASTPIN (-2925 2100) BN 4
J 2
(-2873 2108);
DISPLAY 0.617021 (-2873 2108);
PAINT GREEN (-2873 2108);
FORCEPROP 1 LAST PATH I111
J 2
(-2873 2100);
DISPLAY 0.872340 (-2873 2100);
PAINT GREEN (-2873 2100);
DISPLAY INVISIBLE (-2873 2100);
FORCEPROP 1 LAST HDL_TAP TRUE
J 2
(-3200 1975);
DISPLAY 1.595745 (-3200 1975);
PAINT GREEN (-3200 1975);
DISPLAY INVISIBLE (-3200 1975);
FORCEPROP 1 LAST BODY_TYPE PLUMBING
J 2
(-2875 2050);
DISPLAY 1.595745 (-2875 2050);
PAINT GREEN (-2875 2050);
DISPLAY INVISIBLE (-2875 2050);
FORCEPROP 2 LAST CDS_LIB mstr_standard
J 0
(-2875 2100);
PAINT MONO (-2875 2100);
DISPLAY INVISIBLE (-2875 2100);
FORCEADD TAP..6
R 2
(-2875 2150);
FORCEPROP 3 LASTPIN (-2925 2150) SIG_NAME M_M_MA<5>
J 0
(-2915 2160);
DISPLAY 0.659574 (-2915 2160);
PAINT MONO (-2915 2160);
DISPLAY INVISIBLE (-2915 2160);
FORCEPROP 1 LASTPIN (-2925 2150) BN 5
J 2
(-2873 2158);
DISPLAY 0.617021 (-2873 2158);
PAINT GREEN (-2873 2158);
FORCEPROP 1 LAST PATH I112
J 2
(-2873 2150);
DISPLAY 0.872340 (-2873 2150);
PAINT GREEN (-2873 2150);
DISPLAY INVISIBLE (-2873 2150);
FORCEPROP 1 LAST HDL_TAP TRUE
J 2
(-3200 2025);
DISPLAY 1.595745 (-3200 2025);
PAINT GREEN (-3200 2025);
DISPLAY INVISIBLE (-3200 2025);
FORCEPROP 1 LAST BODY_TYPE PLUMBING
J 2
(-2875 2100);
DISPLAY 1.595745 (-2875 2100);
PAINT GREEN (-2875 2100);
DISPLAY INVISIBLE (-2875 2100);
FORCEPROP 2 LAST CDS_LIB mstr_standard
J 0
(-2875 2150);
PAINT MONO (-2875 2150);
DISPLAY INVISIBLE (-2875 2150);
FORCEADD TAP..6
R 2
(-2875 2200);
FORCEPROP 3 LASTPIN (-2925 2200) SIG_NAME M_M_MA<6>
J 0
(-2915 2210);
DISPLAY 0.659574 (-2915 2210);
PAINT MONO (-2915 2210);
DISPLAY INVISIBLE (-2915 2210);
FORCEPROP 1 LASTPIN (-2925 2200) BN 6
J 2
(-2873 2208);
DISPLAY 0.617021 (-2873 2208);
PAINT GREEN (-2873 2208);
FORCEPROP 1 LAST PATH I113
J 2
(-2873 2200);
DISPLAY 0.872340 (-2873 2200);
PAINT GREEN (-2873 2200);
DISPLAY INVISIBLE (-2873 2200);
FORCEPROP 1 LAST HDL_TAP TRUE
J 2
(-3200 2075);
DISPLAY 1.595745 (-3200 2075);
PAINT GREEN (-3200 2075);
DISPLAY INVISIBLE (-3200 2075);
FORCEPROP 1 LAST BODY_TYPE PLUMBING
J 2
(-2875 2150);
DISPLAY 1.595745 (-2875 2150);
PAINT GREEN (-2875 2150);
DISPLAY INVISIBLE (-2875 2150);
FORCEPROP 2 LAST CDS_LIB mstr_standard
J 0
(-2875 2200);
PAINT MONO (-2875 2200);
DISPLAY INVISIBLE (-2875 2200);
FORCEADD TAP..6
R 2
(-2875 2300);
FORCEPROP 3 LASTPIN (-2925 2300) SIG_NAME M_M_MA<8>
J 0
(-2915 2310);
DISPLAY 0.659574 (-2915 2310);
PAINT MONO (-2915 2310);
DISPLAY INVISIBLE (-2915 2310);
FORCEPROP 1 LASTPIN (-2925 2300) BN 8
J 2
(-2873 2308);
DISPLAY 0.617021 (-2873 2308);
PAINT GREEN (-2873 2308);
FORCEPROP 1 LAST PATH I114
J 2
(-2873 2300);
DISPLAY 0.872340 (-2873 2300);
PAINT GREEN (-2873 2300);
DISPLAY INVISIBLE (-2873 2300);
FORCEPROP 1 LAST HDL_TAP TRUE
J 2
(-3200 2175);
DISPLAY 1.595745 (-3200 2175);
PAINT GREEN (-3200 2175);
DISPLAY INVISIBLE (-3200 2175);
FORCEPROP 1 LAST BODY_TYPE PLUMBING
J 2
(-2875 2250);
DISPLAY 1.595745 (-2875 2250);
PAINT GREEN (-2875 2250);
DISPLAY INVISIBLE (-2875 2250);
FORCEPROP 2 LAST CDS_LIB mstr_standard
J 0
(-2875 2300);
PAINT MONO (-2875 2300);
DISPLAY INVISIBLE (-2875 2300);
FORCEADD TAP..6
R 2
(-2875 2250);
FORCEPROP 3 LASTPIN (-2925 2250) SIG_NAME M_M_MA<7>
J 0
(-2915 2260);
DISPLAY 0.659574 (-2915 2260);
PAINT MONO (-2915 2260);
DISPLAY INVISIBLE (-2915 2260);
FORCEPROP 1 LASTPIN (-2925 2250) BN 7
J 2
(-2873 2258);
DISPLAY 0.617021 (-2873 2258);
PAINT GREEN (-2873 2258);
FORCEPROP 1 LAST PATH I115
J 2
(-2873 2250);
DISPLAY 0.872340 (-2873 2250);
PAINT GREEN (-2873 2250);
DISPLAY INVISIBLE (-2873 2250);
FORCEPROP 1 LAST HDL_TAP TRUE
J 2
(-3200 2125);
DISPLAY 1.595745 (-3200 2125);
PAINT GREEN (-3200 2125);
DISPLAY INVISIBLE (-3200 2125);
FORCEPROP 1 LAST BODY_TYPE PLUMBING
J 2
(-2875 2200);
DISPLAY 1.595745 (-2875 2200);
PAINT GREEN (-2875 2200);
DISPLAY INVISIBLE (-2875 2200);
FORCEPROP 2 LAST CDS_LIB mstr_standard
J 0
(-2875 2250);
PAINT MONO (-2875 2250);
DISPLAY INVISIBLE (-2875 2250);
FORCEADD TAP..6
R 2
(-2875 2450);
FORCEPROP 3 LASTPIN (-2925 2450) SIG_NAME M_M_MA<11>
J 0
(-2915 2460);
DISPLAY 0.659574 (-2915 2460);
PAINT MONO (-2915 2460);
DISPLAY INVISIBLE (-2915 2460);
FORCEPROP 1 LASTPIN (-2925 2450) BN 11
J 2
(-2873 2458);
DISPLAY 0.617021 (-2873 2458);
PAINT GREEN (-2873 2458);
FORCEPROP 1 LAST PATH I116
J 2
(-2873 2450);
DISPLAY 0.872340 (-2873 2450);
PAINT GREEN (-2873 2450);
DISPLAY INVISIBLE (-2873 2450);
FORCEPROP 1 LAST HDL_TAP TRUE
J 2
(-3200 2325);
DISPLAY 1.595745 (-3200 2325);
PAINT GREEN (-3200 2325);
DISPLAY INVISIBLE (-3200 2325);
FORCEPROP 1 LAST BODY_TYPE PLUMBING
J 2
(-2875 2400);
DISPLAY 1.595745 (-2875 2400);
PAINT GREEN (-2875 2400);
DISPLAY INVISIBLE (-2875 2400);
FORCEPROP 2 LAST CDS_LIB mstr_standard
J 0
(-2875 2450);
PAINT MONO (-2875 2450);
DISPLAY INVISIBLE (-2875 2450);
FORCEADD TAP..6
R 2
(-2875 2400);
FORCEPROP 3 LASTPIN (-2925 2400) SIG_NAME M_M_MA<10>
J 0
(-2915 2410);
DISPLAY 0.659574 (-2915 2410);
PAINT MONO (-2915 2410);
DISPLAY INVISIBLE (-2915 2410);
FORCEPROP 1 LASTPIN (-2925 2400) BN 10
J 2
(-2873 2408);
DISPLAY 0.617021 (-2873 2408);
PAINT GREEN (-2873 2408);
FORCEPROP 1 LAST PATH I117
J 2
(-2873 2400);
DISPLAY 0.872340 (-2873 2400);
PAINT GREEN (-2873 2400);
DISPLAY INVISIBLE (-2873 2400);
FORCEPROP 1 LAST HDL_TAP TRUE
J 2
(-3200 2275);
DISPLAY 1.595745 (-3200 2275);
PAINT GREEN (-3200 2275);
DISPLAY INVISIBLE (-3200 2275);
FORCEPROP 1 LAST BODY_TYPE PLUMBING
J 2
(-2875 2350);
DISPLAY 1.595745 (-2875 2350);
PAINT GREEN (-2875 2350);
DISPLAY INVISIBLE (-2875 2350);
FORCEPROP 2 LAST CDS_LIB mstr_standard
J 0
(-2875 2400);
PAINT MONO (-2875 2400);
DISPLAY INVISIBLE (-2875 2400);
FORCEADD TAP..6
R 2
(-2875 2350);
FORCEPROP 3 LASTPIN (-2925 2350) SIG_NAME M_M_MA<9>
J 0
(-2915 2360);
DISPLAY 0.659574 (-2915 2360);
PAINT MONO (-2915 2360);
DISPLAY INVISIBLE (-2915 2360);
FORCEPROP 1 LASTPIN (-2925 2350) BN 9
J 2
(-2873 2358);
DISPLAY 0.617021 (-2873 2358);
PAINT GREEN (-2873 2358);
FORCEPROP 1 LAST PATH I118
J 2
(-2873 2350);
DISPLAY 0.872340 (-2873 2350);
PAINT GREEN (-2873 2350);
DISPLAY INVISIBLE (-2873 2350);
FORCEPROP 1 LAST HDL_TAP TRUE
J 2
(-3200 2225);
DISPLAY 1.595745 (-3200 2225);
PAINT GREEN (-3200 2225);
DISPLAY INVISIBLE (-3200 2225);
FORCEPROP 1 LAST BODY_TYPE PLUMBING
J 2
(-2875 2300);
DISPLAY 1.595745 (-2875 2300);
PAINT GREEN (-2875 2300);
DISPLAY INVISIBLE (-2875 2300);
FORCEPROP 2 LAST CDS_LIB mstr_standard
J 0
(-2875 2350);
PAINT MONO (-2875 2350);
DISPLAY INVISIBLE (-2875 2350);
FORCEADD TAP..6
R 2
(-2875 2500);
FORCEPROP 3 LASTPIN (-2925 2500) SIG_NAME M_M_MA<12>
J 0
(-2915 2510);
DISPLAY 0.659574 (-2915 2510);
PAINT MONO (-2915 2510);
DISPLAY INVISIBLE (-2915 2510);
FORCEPROP 1 LASTPIN (-2925 2500) BN 12
J 2
(-2873 2508);
DISPLAY 0.617021 (-2873 2508);
PAINT GREEN (-2873 2508);
FORCEPROP 1 LAST PATH I119
J 2
(-2873 2500);
DISPLAY 0.872340 (-2873 2500);
PAINT GREEN (-2873 2500);
DISPLAY INVISIBLE (-2873 2500);
FORCEPROP 1 LAST HDL_TAP TRUE
J 2
(-3200 2375);
DISPLAY 1.595745 (-3200 2375);
PAINT GREEN (-3200 2375);
DISPLAY INVISIBLE (-3200 2375);
FORCEPROP 1 LAST BODY_TYPE PLUMBING
J 2
(-2875 2450);
DISPLAY 1.595745 (-2875 2450);
PAINT GREEN (-2875 2450);
DISPLAY INVISIBLE (-2875 2450);
FORCEPROP 2 LAST CDS_LIB mstr_standard
J 0
(-2875 2500);
PAINT MONO (-2875 2500);
DISPLAY INVISIBLE (-2875 2500);
FORCEADD TAP..6
(-5600 950);
FORCEPROP 3 LASTPIN (-5550 950) SIG_NAME M_M_CLK_DP<3>
J 0
(-5540 960);
DISPLAY 0.659574 (-5540 960);
PAINT MONO (-5540 960);
DISPLAY INVISIBLE (-5540 960);
FORCEPROP 1 LASTPIN (-5550 950) BN 3
J 0
(-5602 958);
DISPLAY 0.617021 (-5602 958);
PAINT GREEN (-5602 958);
FORCEPROP 1 LAST PATH I12
J 0
(-5602 950);
DISPLAY 0.872340 (-5602 950);
PAINT GREEN (-5602 950);
DISPLAY INVISIBLE (-5602 950);
FORCEPROP 1 LAST HDL_TAP TRUE
J 0
(-5275 825);
DISPLAY 1.595745 (-5275 825);
PAINT GREEN (-5275 825);
DISPLAY INVISIBLE (-5275 825);
FORCEPROP 1 LAST BODY_TYPE PLUMBING
J 0
(-5600 900);
DISPLAY 1.595745 (-5600 900);
PAINT GREEN (-5600 900);
DISPLAY INVISIBLE (-5600 900);
FORCEPROP 2 LAST CDS_LIB mstr_standard
J 0
(-5600 950);
PAINT MONO (-5600 950);
DISPLAY INVISIBLE (-5600 950);
FORCEADD TAP..6
R 2
(-2875 2550);
FORCEPROP 3 LASTPIN (-2925 2550) SIG_NAME M_M_MA<13>
J 0
(-2915 2560);
DISPLAY 0.659574 (-2915 2560);
PAINT MONO (-2915 2560);
DISPLAY INVISIBLE (-2915 2560);
FORCEPROP 1 LASTPIN (-2925 2550) BN 13
J 2
(-2873 2558);
DISPLAY 0.617021 (-2873 2558);
PAINT GREEN (-2873 2558);
FORCEPROP 1 LAST PATH I120
J 2
(-2873 2550);
DISPLAY 0.872340 (-2873 2550);
PAINT GREEN (-2873 2550);
DISPLAY INVISIBLE (-2873 2550);
FORCEPROP 1 LAST HDL_TAP TRUE
J 2
(-3200 2425);
DISPLAY 1.595745 (-3200 2425);
PAINT GREEN (-3200 2425);
DISPLAY INVISIBLE (-3200 2425);
FORCEPROP 1 LAST BODY_TYPE PLUMBING
J 2
(-2875 2500);
DISPLAY 1.595745 (-2875 2500);
PAINT GREEN (-2875 2500);
DISPLAY INVISIBLE (-2875 2500);
FORCEPROP 2 LAST CDS_LIB mstr_standard
J 0
(-2875 2550);
PAINT MONO (-2875 2550);
DISPLAY INVISIBLE (-2875 2550);
FORCEADD TAP..6
R 2
(-2875 2600);
FORCEPROP 3 LASTPIN (-2925 2600) SIG_NAME M_M_MA<14>
J 0
(-2915 2610);
DISPLAY 0.659574 (-2915 2610);
PAINT MONO (-2915 2610);
DISPLAY INVISIBLE (-2915 2610);
FORCEPROP 1 LASTPIN (-2925 2600) BN 14
J 2
(-2873 2608);
DISPLAY 0.617021 (-2873 2608);
PAINT GREEN (-2873 2608);
FORCEPROP 1 LAST PATH I121
J 2
(-2873 2600);
DISPLAY 0.872340 (-2873 2600);
PAINT GREEN (-2873 2600);
DISPLAY INVISIBLE (-2873 2600);
FORCEPROP 1 LAST HDL_TAP TRUE
J 2
(-3200 2475);
DISPLAY 1.595745 (-3200 2475);
PAINT GREEN (-3200 2475);
DISPLAY INVISIBLE (-3200 2475);
FORCEPROP 1 LAST BODY_TYPE PLUMBING
J 2
(-2875 2550);
DISPLAY 1.595745 (-2875 2550);
PAINT GREEN (-2875 2550);
DISPLAY INVISIBLE (-2875 2550);
FORCEPROP 2 LAST CDS_LIB mstr_standard
J 0
(-2875 2600);
PAINT MONO (-2875 2600);
DISPLAY INVISIBLE (-2875 2600);
FORCEADD TAP..6
R 2
(-2875 2650);
FORCEPROP 3 LASTPIN (-2925 2650) SIG_NAME M_M_MA<15>
J 0
(-2915 2660);
DISPLAY 0.659574 (-2915 2660);
PAINT MONO (-2915 2660);
DISPLAY INVISIBLE (-2915 2660);
FORCEPROP 1 LASTPIN (-2925 2650) BN 15
J 2
(-2873 2658);
DISPLAY 0.617021 (-2873 2658);
PAINT GREEN (-2873 2658);
FORCEPROP 1 LAST PATH I122
J 2
(-2873 2650);
DISPLAY 0.872340 (-2873 2650);
PAINT GREEN (-2873 2650);
DISPLAY INVISIBLE (-2873 2650);
FORCEPROP 1 LAST HDL_TAP TRUE
J 2
(-3200 2525);
DISPLAY 1.595745 (-3200 2525);
PAINT GREEN (-3200 2525);
DISPLAY INVISIBLE (-3200 2525);
FORCEPROP 1 LAST BODY_TYPE PLUMBING
J 2
(-2875 2600);
DISPLAY 1.595745 (-2875 2600);
PAINT GREEN (-2875 2600);
DISPLAY INVISIBLE (-2875 2600);
FORCEPROP 2 LAST CDS_LIB mstr_standard
J 0
(-2875 2650);
PAINT MONO (-2875 2650);
DISPLAY INVISIBLE (-2875 2650);
FORCEADD TAP..6
R 2
(-2875 2700);
FORCEPROP 3 LASTPIN (-2925 2700) SIG_NAME M_M_MA<16>
J 0
(-2915 2710);
DISPLAY 0.659574 (-2915 2710);
PAINT MONO (-2915 2710);
DISPLAY INVISIBLE (-2915 2710);
FORCEPROP 1 LASTPIN (-2925 2700) BN 16
J 2
(-2873 2708);
DISPLAY 0.617021 (-2873 2708);
PAINT GREEN (-2873 2708);
FORCEPROP 1 LAST PATH I123
J 2
(-2873 2700);
DISPLAY 0.872340 (-2873 2700);
PAINT GREEN (-2873 2700);
DISPLAY INVISIBLE (-2873 2700);
FORCEPROP 1 LAST HDL_TAP TRUE
J 2
(-3200 2575);
DISPLAY 1.595745 (-3200 2575);
PAINT GREEN (-3200 2575);
DISPLAY INVISIBLE (-3200 2575);
FORCEPROP 1 LAST BODY_TYPE PLUMBING
J 2
(-2875 2650);
DISPLAY 1.595745 (-2875 2650);
PAINT GREEN (-2875 2650);
DISPLAY INVISIBLE (-2875 2650);
FORCEPROP 2 LAST CDS_LIB mstr_standard
J 0
(-2875 2700);
PAINT MONO (-2875 2700);
DISPLAY INVISIBLE (-2875 2700);
FORCEADD TAP..6
R 2
(-2875 2750);
FORCEPROP 3 LASTPIN (-2925 2750) SIG_NAME M_M_MA<17>
J 0
(-2915 2760);
DISPLAY 0.659574 (-2915 2760);
PAINT MONO (-2915 2760);
DISPLAY INVISIBLE (-2915 2760);
FORCEPROP 1 LASTPIN (-2925 2750) BN 17
J 2
(-2873 2758);
DISPLAY 0.617021 (-2873 2758);
PAINT GREEN (-2873 2758);
FORCEPROP 1 LAST PATH I124
J 2
(-2873 2750);
DISPLAY 0.872340 (-2873 2750);
PAINT GREEN (-2873 2750);
DISPLAY INVISIBLE (-2873 2750);
FORCEPROP 1 LAST HDL_TAP TRUE
J 2
(-3200 2625);
DISPLAY 1.595745 (-3200 2625);
PAINT GREEN (-3200 2625);
DISPLAY INVISIBLE (-3200 2625);
FORCEPROP 1 LAST BODY_TYPE PLUMBING
J 2
(-2875 2700);
DISPLAY 1.595745 (-2875 2700);
PAINT GREEN (-2875 2700);
DISPLAY INVISIBLE (-2875 2700);
FORCEPROP 2 LAST CDS_LIB mstr_standard
J 0
(-2875 2750);
PAINT MONO (-2875 2750);
DISPLAY INVISIBLE (-2875 2750);
FORCEADD TAP..6
R 2
(-2875 2900);
FORCEPROP 3 LASTPIN (-2925 2900) SIG_NAME M_M_DQS_DN<1>
J 0
(-2915 2910);
DISPLAY 0.659574 (-2915 2910);
PAINT MONO (-2915 2910);
DISPLAY INVISIBLE (-2915 2910);
FORCEPROP 1 LASTPIN (-2925 2900) BN 1
J 2
(-2873 2908);
DISPLAY 0.617021 (-2873 2908);
PAINT GREEN (-2873 2908);
FORCEPROP 1 LAST PATH I125
J 2
(-2873 2900);
DISPLAY 0.872340 (-2873 2900);
PAINT GREEN (-2873 2900);
DISPLAY INVISIBLE (-2873 2900);
FORCEPROP 1 LAST HDL_TAP TRUE
J 2
(-3200 2775);
DISPLAY 1.595745 (-3200 2775);
PAINT GREEN (-3200 2775);
DISPLAY INVISIBLE (-3200 2775);
FORCEPROP 1 LAST BODY_TYPE PLUMBING
J 2
(-2875 2850);
DISPLAY 1.595745 (-2875 2850);
PAINT GREEN (-2875 2850);
DISPLAY INVISIBLE (-2875 2850);
FORCEPROP 2 LAST CDS_LIB mstr_standard
J 0
(-2875 2900);
PAINT MONO (-2875 2900);
DISPLAY INVISIBLE (-2875 2900);
FORCEADD TAP..6
R 2
(-2875 2950);
FORCEPROP 3 LASTPIN (-2925 2950) SIG_NAME M_M_DQS_DN<2>
J 0
(-2915 2960);
DISPLAY 0.659574 (-2915 2960);
PAINT MONO (-2915 2960);
DISPLAY INVISIBLE (-2915 2960);
FORCEPROP 1 LASTPIN (-2925 2950) BN 2
J 2
(-2873 2958);
DISPLAY 0.617021 (-2873 2958);
PAINT GREEN (-2873 2958);
FORCEPROP 1 LAST PATH I126
J 2
(-2873 2950);
DISPLAY 0.872340 (-2873 2950);
PAINT GREEN (-2873 2950);
DISPLAY INVISIBLE (-2873 2950);
FORCEPROP 1 LAST HDL_TAP TRUE
J 2
(-3200 2825);
DISPLAY 1.595745 (-3200 2825);
PAINT GREEN (-3200 2825);
DISPLAY INVISIBLE (-3200 2825);
FORCEPROP 1 LAST BODY_TYPE PLUMBING
J 2
(-2875 2900);
DISPLAY 1.595745 (-2875 2900);
PAINT GREEN (-2875 2900);
DISPLAY INVISIBLE (-2875 2900);
FORCEPROP 2 LAST CDS_LIB mstr_standard
J 0
(-2875 2950);
PAINT MONO (-2875 2950);
DISPLAY INVISIBLE (-2875 2950);
FORCEADD TAP..6
R 2
(-2875 2850);
FORCEPROP 3 LASTPIN (-2925 2850) SIG_NAME M_M_DQS_DN<0>
J 0
(-2915 2860);
DISPLAY 0.659574 (-2915 2860);
PAINT MONO (-2915 2860);
DISPLAY INVISIBLE (-2915 2860);
FORCEPROP 1 LASTPIN (-2925 2850) BN 0
J 2
(-2873 2858);
DISPLAY 0.617021 (-2873 2858);
PAINT GREEN (-2873 2858);
FORCEPROP 1 LAST PATH I127
J 2
(-2873 2850);
DISPLAY 0.872340 (-2873 2850);
PAINT GREEN (-2873 2850);
DISPLAY INVISIBLE (-2873 2850);
FORCEPROP 1 LAST HDL_TAP TRUE
J 2
(-3200 2725);
DISPLAY 1.595745 (-3200 2725);
PAINT GREEN (-3200 2725);
DISPLAY INVISIBLE (-3200 2725);
FORCEPROP 1 LAST BODY_TYPE PLUMBING
J 2
(-2875 2800);
DISPLAY 1.595745 (-2875 2800);
PAINT GREEN (-2875 2800);
DISPLAY INVISIBLE (-2875 2800);
FORCEPROP 2 LAST CDS_LIB mstr_standard
J 0
(-2875 2850);
PAINT MONO (-2875 2850);
DISPLAY INVISIBLE (-2875 2850);
FORCEADD TAP..6
R 2
(-2875 3050);
FORCEPROP 3 LASTPIN (-2925 3050) SIG_NAME M_M_DQS_DN<4>
J 0
(-2915 3060);
DISPLAY 0.659574 (-2915 3060);
PAINT MONO (-2915 3060);
DISPLAY INVISIBLE (-2915 3060);
FORCEPROP 1 LASTPIN (-2925 3050) BN 4
J 2
(-2873 3058);
DISPLAY 0.617021 (-2873 3058);
PAINT GREEN (-2873 3058);
FORCEPROP 1 LAST PATH I128
J 2
(-2873 3050);
DISPLAY 0.872340 (-2873 3050);
PAINT GREEN (-2873 3050);
DISPLAY INVISIBLE (-2873 3050);
FORCEPROP 1 LAST HDL_TAP TRUE
J 2
(-3200 2925);
DISPLAY 1.595745 (-3200 2925);
PAINT GREEN (-3200 2925);
DISPLAY INVISIBLE (-3200 2925);
FORCEPROP 1 LAST BODY_TYPE PLUMBING
J 2
(-2875 3000);
DISPLAY 1.595745 (-2875 3000);
PAINT GREEN (-2875 3000);
DISPLAY INVISIBLE (-2875 3000);
FORCEPROP 2 LAST CDS_LIB mstr_standard
J 0
(-2875 3050);
PAINT MONO (-2875 3050);
DISPLAY INVISIBLE (-2875 3050);
FORCEADD TAP..6
R 2
(-2875 3000);
FORCEPROP 3 LASTPIN (-2925 3000) SIG_NAME M_M_DQS_DN<3>
J 0
(-2915 3010);
DISPLAY 0.659574 (-2915 3010);
PAINT MONO (-2915 3010);
DISPLAY INVISIBLE (-2915 3010);
FORCEPROP 1 LASTPIN (-2925 3000) BN 3
J 2
(-2873 3008);
DISPLAY 0.617021 (-2873 3008);
PAINT GREEN (-2873 3008);
FORCEPROP 1 LAST PATH I129
J 2
(-2873 3000);
DISPLAY 0.872340 (-2873 3000);
PAINT GREEN (-2873 3000);
DISPLAY INVISIBLE (-2873 3000);
FORCEPROP 1 LAST HDL_TAP TRUE
J 2
(-3200 2875);
DISPLAY 1.595745 (-3200 2875);
PAINT GREEN (-3200 2875);
DISPLAY INVISIBLE (-3200 2875);
FORCEPROP 1 LAST BODY_TYPE PLUMBING
J 2
(-2875 2950);
DISPLAY 1.595745 (-2875 2950);
PAINT GREEN (-2875 2950);
DISPLAY INVISIBLE (-2875 2950);
FORCEPROP 2 LAST CDS_LIB mstr_standard
J 0
(-2875 3000);
PAINT MONO (-2875 3000);
DISPLAY INVISIBLE (-2875 3000);
FORCEADD TAP..6
(-5600 1050);
FORCEPROP 3 LASTPIN (-5550 1050) SIG_NAME M_M_ECC<0>
J 0
(-5540 1060);
DISPLAY 0.659574 (-5540 1060);
PAINT MONO (-5540 1060);
DISPLAY INVISIBLE (-5540 1060);
FORCEPROP 1 LASTPIN (-5550 1050) BN 0
J 0
(-5602 1058);
DISPLAY 0.617021 (-5602 1058);
PAINT GREEN (-5602 1058);
FORCEPROP 1 LAST PATH I13
J 0
(-5602 1050);
DISPLAY 0.872340 (-5602 1050);
PAINT GREEN (-5602 1050);
DISPLAY INVISIBLE (-5602 1050);
FORCEPROP 1 LAST HDL_TAP TRUE
J 0
(-5275 925);
DISPLAY 1.595745 (-5275 925);
PAINT GREEN (-5275 925);
DISPLAY INVISIBLE (-5275 925);
FORCEPROP 1 LAST BODY_TYPE PLUMBING
J 0
(-5600 1000);
DISPLAY 1.595745 (-5600 1000);
PAINT GREEN (-5600 1000);
DISPLAY INVISIBLE (-5600 1000);
FORCEPROP 2 LAST CDS_LIB mstr_standard
J 0
(-5600 1050);
PAINT MONO (-5600 1050);
DISPLAY INVISIBLE (-5600 1050);
FORCEADD TAP..6
R 2
(-2875 3100);
FORCEPROP 3 LASTPIN (-2925 3100) SIG_NAME M_M_DQS_DN<5>
J 0
(-2915 3110);
DISPLAY 0.659574 (-2915 3110);
PAINT MONO (-2915 3110);
DISPLAY INVISIBLE (-2915 3110);
FORCEPROP 1 LASTPIN (-2925 3100) BN 5
J 2
(-2873 3108);
DISPLAY 0.617021 (-2873 3108);
PAINT GREEN (-2873 3108);
FORCEPROP 1 LAST PATH I130
J 2
(-2873 3100);
DISPLAY 0.872340 (-2873 3100);
PAINT GREEN (-2873 3100);
DISPLAY INVISIBLE (-2873 3100);
FORCEPROP 1 LAST HDL_TAP TRUE
J 2
(-3200 2975);
DISPLAY 1.595745 (-3200 2975);
PAINT GREEN (-3200 2975);
DISPLAY INVISIBLE (-3200 2975);
FORCEPROP 1 LAST BODY_TYPE PLUMBING
J 2
(-2875 3050);
DISPLAY 1.595745 (-2875 3050);
PAINT GREEN (-2875 3050);
DISPLAY INVISIBLE (-2875 3050);
FORCEPROP 2 LAST CDS_LIB mstr_standard
J 0
(-2875 3100);
PAINT MONO (-2875 3100);
DISPLAY INVISIBLE (-2875 3100);
FORCEADD TAP..6
R 2
(-2875 3150);
FORCEPROP 3 LASTPIN (-2925 3150) SIG_NAME M_M_DQS_DN<6>
J 0
(-2915 3160);
DISPLAY 0.659574 (-2915 3160);
PAINT MONO (-2915 3160);
DISPLAY INVISIBLE (-2915 3160);
FORCEPROP 1 LASTPIN (-2925 3150) BN 6
J 2
(-2873 3158);
DISPLAY 0.617021 (-2873 3158);
PAINT GREEN (-2873 3158);
FORCEPROP 1 LAST PATH I131
J 2
(-2873 3150);
DISPLAY 0.872340 (-2873 3150);
PAINT GREEN (-2873 3150);
DISPLAY INVISIBLE (-2873 3150);
FORCEPROP 1 LAST HDL_TAP TRUE
J 2
(-3200 3025);
DISPLAY 1.595745 (-3200 3025);
PAINT GREEN (-3200 3025);
DISPLAY INVISIBLE (-3200 3025);
FORCEPROP 1 LAST BODY_TYPE PLUMBING
J 2
(-2875 3100);
DISPLAY 1.595745 (-2875 3100);
PAINT GREEN (-2875 3100);
DISPLAY INVISIBLE (-2875 3100);
FORCEPROP 2 LAST CDS_LIB mstr_standard
J 0
(-2875 3150);
PAINT MONO (-2875 3150);
DISPLAY INVISIBLE (-2875 3150);
FORCEADD TAP..6
R 2
(-2875 3200);
FORCEPROP 3 LASTPIN (-2925 3200) SIG_NAME M_M_DQS_DN<7>
J 0
(-2915 3210);
DISPLAY 0.659574 (-2915 3210);
PAINT MONO (-2915 3210);
DISPLAY INVISIBLE (-2915 3210);
FORCEPROP 1 LASTPIN (-2925 3200) BN 7
J 2
(-2873 3208);
DISPLAY 0.617021 (-2873 3208);
PAINT GREEN (-2873 3208);
FORCEPROP 1 LAST PATH I132
J 2
(-2873 3200);
DISPLAY 0.872340 (-2873 3200);
PAINT GREEN (-2873 3200);
DISPLAY INVISIBLE (-2873 3200);
FORCEPROP 1 LAST HDL_TAP TRUE
J 2
(-3200 3075);
DISPLAY 1.595745 (-3200 3075);
PAINT GREEN (-3200 3075);
DISPLAY INVISIBLE (-3200 3075);
FORCEPROP 1 LAST BODY_TYPE PLUMBING
J 2
(-2875 3150);
DISPLAY 1.595745 (-2875 3150);
PAINT GREEN (-2875 3150);
DISPLAY INVISIBLE (-2875 3150);
FORCEPROP 2 LAST CDS_LIB mstr_standard
J 0
(-2875 3200);
PAINT MONO (-2875 3200);
DISPLAY INVISIBLE (-2875 3200);
FORCEADD TAP..6
R 2
(-2875 3250);
FORCEPROP 3 LASTPIN (-2925 3250) SIG_NAME M_M_DQS_DN<8>
J 0
(-2915 3260);
DISPLAY 0.659574 (-2915 3260);
PAINT MONO (-2915 3260);
DISPLAY INVISIBLE (-2915 3260);
FORCEPROP 1 LASTPIN (-2925 3250) BN 8
J 2
(-2873 3258);
DISPLAY 0.617021 (-2873 3258);
PAINT GREEN (-2873 3258);
FORCEPROP 1 LAST PATH I133
J 2
(-2873 3250);
DISPLAY 0.872340 (-2873 3250);
PAINT GREEN (-2873 3250);
DISPLAY INVISIBLE (-2873 3250);
FORCEPROP 1 LAST HDL_TAP TRUE
J 2
(-3200 3125);
DISPLAY 1.595745 (-3200 3125);
PAINT GREEN (-3200 3125);
DISPLAY INVISIBLE (-3200 3125);
FORCEPROP 1 LAST BODY_TYPE PLUMBING
J 2
(-2875 3200);
DISPLAY 1.595745 (-2875 3200);
PAINT GREEN (-2875 3200);
DISPLAY INVISIBLE (-2875 3200);
FORCEPROP 2 LAST CDS_LIB mstr_standard
J 0
(-2875 3250);
PAINT MONO (-2875 3250);
DISPLAY INVISIBLE (-2875 3250);
FORCEADD TAP..6
R 2
(-2875 3300);
FORCEPROP 3 LASTPIN (-2925 3300) SIG_NAME M_M_DQS_DN<9>
J 0
(-2915 3310);
DISPLAY 0.659574 (-2915 3310);
PAINT MONO (-2915 3310);
DISPLAY INVISIBLE (-2915 3310);
FORCEPROP 1 LASTPIN (-2925 3300) BN 9
J 2
(-2873 3308);
DISPLAY 0.617021 (-2873 3308);
PAINT GREEN (-2873 3308);
FORCEPROP 1 LAST PATH I134
J 2
(-2873 3300);
DISPLAY 0.872340 (-2873 3300);
PAINT GREEN (-2873 3300);
DISPLAY INVISIBLE (-2873 3300);
FORCEPROP 1 LAST HDL_TAP TRUE
J 2
(-3200 3175);
DISPLAY 1.595745 (-3200 3175);
PAINT GREEN (-3200 3175);
DISPLAY INVISIBLE (-3200 3175);
FORCEPROP 1 LAST BODY_TYPE PLUMBING
J 2
(-2875 3250);
DISPLAY 1.595745 (-2875 3250);
PAINT GREEN (-2875 3250);
DISPLAY INVISIBLE (-2875 3250);
FORCEPROP 2 LAST CDS_LIB mstr_standard
J 0
(-2875 3300);
PAINT MONO (-2875 3300);
DISPLAY INVISIBLE (-2875 3300);
FORCEADD TAP..6
R 2
(-2875 3350);
FORCEPROP 3 LASTPIN (-2925 3350) SIG_NAME M_M_DQS_DN<10>
J 0
(-2915 3360);
DISPLAY 0.659574 (-2915 3360);
PAINT MONO (-2915 3360);
DISPLAY INVISIBLE (-2915 3360);
FORCEPROP 1 LASTPIN (-2925 3350) BN 10
J 2
(-2873 3358);
DISPLAY 0.617021 (-2873 3358);
PAINT GREEN (-2873 3358);
FORCEPROP 1 LAST PATH I135
J 2
(-2873 3350);
DISPLAY 0.872340 (-2873 3350);
PAINT GREEN (-2873 3350);
DISPLAY INVISIBLE (-2873 3350);
FORCEPROP 1 LAST HDL_TAP TRUE
J 2
(-3200 3225);
DISPLAY 1.595745 (-3200 3225);
PAINT GREEN (-3200 3225);
DISPLAY INVISIBLE (-3200 3225);
FORCEPROP 1 LAST BODY_TYPE PLUMBING
J 2
(-2875 3300);
DISPLAY 1.595745 (-2875 3300);
PAINT GREEN (-2875 3300);
DISPLAY INVISIBLE (-2875 3300);
FORCEPROP 2 LAST CDS_LIB mstr_standard
J 0
(-2875 3350);
PAINT MONO (-2875 3350);
DISPLAY INVISIBLE (-2875 3350);
FORCEADD TAP..6
R 2
(-2875 3450);
FORCEPROP 3 LASTPIN (-2925 3450) SIG_NAME M_M_DQS_DN<12>
J 0
(-2915 3460);
DISPLAY 0.659574 (-2915 3460);
PAINT MONO (-2915 3460);
DISPLAY INVISIBLE (-2915 3460);
FORCEPROP 1 LASTPIN (-2925 3450) BN 12
J 2
(-2873 3458);
DISPLAY 0.617021 (-2873 3458);
PAINT GREEN (-2873 3458);
FORCEPROP 1 LAST PATH I136
J 2
(-2873 3450);
DISPLAY 0.872340 (-2873 3450);
PAINT GREEN (-2873 3450);
DISPLAY INVISIBLE (-2873 3450);
FORCEPROP 1 LAST HDL_TAP TRUE
J 2
(-3200 3325);
DISPLAY 1.595745 (-3200 3325);
PAINT GREEN (-3200 3325);
DISPLAY INVISIBLE (-3200 3325);
FORCEPROP 1 LAST BODY_TYPE PLUMBING
J 2
(-2875 3400);
DISPLAY 1.595745 (-2875 3400);
PAINT GREEN (-2875 3400);
DISPLAY INVISIBLE (-2875 3400);
FORCEPROP 2 LAST CDS_LIB mstr_standard
J 0
(-2875 3450);
PAINT MONO (-2875 3450);
DISPLAY INVISIBLE (-2875 3450);
FORCEADD TAP..6
R 2
(-2875 3400);
FORCEPROP 3 LASTPIN (-2925 3400) SIG_NAME M_M_DQS_DN<11>
J 0
(-2915 3410);
DISPLAY 0.659574 (-2915 3410);
PAINT MONO (-2915 3410);
DISPLAY INVISIBLE (-2915 3410);
FORCEPROP 1 LASTPIN (-2925 3400) BN 11
J 2
(-2873 3408);
DISPLAY 0.617021 (-2873 3408);
PAINT GREEN (-2873 3408);
FORCEPROP 1 LAST PATH I137
J 2
(-2873 3400);
DISPLAY 0.872340 (-2873 3400);
PAINT GREEN (-2873 3400);
DISPLAY INVISIBLE (-2873 3400);
FORCEPROP 1 LAST HDL_TAP TRUE
J 2
(-3200 3275);
DISPLAY 1.595745 (-3200 3275);
PAINT GREEN (-3200 3275);
DISPLAY INVISIBLE (-3200 3275);
FORCEPROP 1 LAST BODY_TYPE PLUMBING
J 2
(-2875 3350);
DISPLAY 1.595745 (-2875 3350);
PAINT GREEN (-2875 3350);
DISPLAY INVISIBLE (-2875 3350);
FORCEPROP 2 LAST CDS_LIB mstr_standard
J 0
(-2875 3400);
PAINT MONO (-2875 3400);
DISPLAY INVISIBLE (-2875 3400);
FORCEADD TAP..6
R 2
(-2875 3600);
FORCEPROP 3 LASTPIN (-2925 3600) SIG_NAME M_M_DQS_DN<15>
J 0
(-2915 3610);
DISPLAY 0.659574 (-2915 3610);
PAINT MONO (-2915 3610);
DISPLAY INVISIBLE (-2915 3610);
FORCEPROP 1 LASTPIN (-2925 3600) BN 15
J 2
(-2873 3608);
DISPLAY 0.617021 (-2873 3608);
PAINT GREEN (-2873 3608);
FORCEPROP 1 LAST PATH I138
J 2
(-2873 3600);
DISPLAY 0.872340 (-2873 3600);
PAINT GREEN (-2873 3600);
DISPLAY INVISIBLE (-2873 3600);
FORCEPROP 1 LAST HDL_TAP TRUE
J 2
(-3200 3475);
DISPLAY 1.595745 (-3200 3475);
PAINT GREEN (-3200 3475);
DISPLAY INVISIBLE (-3200 3475);
FORCEPROP 1 LAST BODY_TYPE PLUMBING
J 2
(-2875 3550);
DISPLAY 1.595745 (-2875 3550);
PAINT GREEN (-2875 3550);
DISPLAY INVISIBLE (-2875 3550);
FORCEPROP 2 LAST CDS_LIB mstr_standard
J 0
(-2875 3600);
PAINT MONO (-2875 3600);
DISPLAY INVISIBLE (-2875 3600);
FORCEADD TAP..6
R 2
(-2875 3550);
FORCEPROP 3 LASTPIN (-2925 3550) SIG_NAME M_M_DQS_DN<14>
J 0
(-2915 3560);
DISPLAY 0.659574 (-2915 3560);
PAINT MONO (-2915 3560);
DISPLAY INVISIBLE (-2915 3560);
FORCEPROP 1 LASTPIN (-2925 3550) BN 14
J 2
(-2873 3558);
DISPLAY 0.617021 (-2873 3558);
PAINT GREEN (-2873 3558);
FORCEPROP 1 LAST PATH I139
J 2
(-2873 3550);
DISPLAY 0.872340 (-2873 3550);
PAINT GREEN (-2873 3550);
DISPLAY INVISIBLE (-2873 3550);
FORCEPROP 1 LAST HDL_TAP TRUE
J 2
(-3200 3425);
DISPLAY 1.595745 (-3200 3425);
PAINT GREEN (-3200 3425);
DISPLAY INVISIBLE (-3200 3425);
FORCEPROP 1 LAST BODY_TYPE PLUMBING
J 2
(-2875 3500);
DISPLAY 1.595745 (-2875 3500);
PAINT GREEN (-2875 3500);
DISPLAY INVISIBLE (-2875 3500);
FORCEPROP 2 LAST CDS_LIB mstr_standard
J 0
(-2875 3550);
PAINT MONO (-2875 3550);
DISPLAY INVISIBLE (-2875 3550);
FORCEADD TAP..6
(-5600 1100);
FORCEPROP 3 LASTPIN (-5550 1100) SIG_NAME M_M_ECC<1>
J 0
(-5540 1110);
DISPLAY 0.659574 (-5540 1110);
PAINT MONO (-5540 1110);
DISPLAY INVISIBLE (-5540 1110);
FORCEPROP 1 LASTPIN (-5550 1100) BN 1
J 0
(-5602 1108);
DISPLAY 0.617021 (-5602 1108);
PAINT GREEN (-5602 1108);
FORCEPROP 1 LAST PATH I14
J 0
(-5602 1100);
DISPLAY 0.872340 (-5602 1100);
PAINT GREEN (-5602 1100);
DISPLAY INVISIBLE (-5602 1100);
FORCEPROP 1 LAST HDL_TAP TRUE
J 0
(-5275 975);
DISPLAY 1.595745 (-5275 975);
PAINT GREEN (-5275 975);
DISPLAY INVISIBLE (-5275 975);
FORCEPROP 1 LAST BODY_TYPE PLUMBING
J 0
(-5600 1050);
DISPLAY 1.595745 (-5600 1050);
PAINT GREEN (-5600 1050);
DISPLAY INVISIBLE (-5600 1050);
FORCEPROP 2 LAST CDS_LIB mstr_standard
J 0
(-5600 1100);
PAINT MONO (-5600 1100);
DISPLAY INVISIBLE (-5600 1100);
FORCEADD TAP..6
R 2
(-2875 3500);
FORCEPROP 3 LASTPIN (-2925 3500) SIG_NAME M_M_DQS_DN<13>
J 0
(-2915 3510);
DISPLAY 0.659574 (-2915 3510);
PAINT MONO (-2915 3510);
DISPLAY INVISIBLE (-2915 3510);
FORCEPROP 1 LASTPIN (-2925 3500) BN 13
J 2
(-2873 3508);
DISPLAY 0.617021 (-2873 3508);
PAINT GREEN (-2873 3508);
FORCEPROP 1 LAST PATH I140
J 2
(-2873 3500);
DISPLAY 0.872340 (-2873 3500);
PAINT GREEN (-2873 3500);
DISPLAY INVISIBLE (-2873 3500);
FORCEPROP 1 LAST HDL_TAP TRUE
J 2
(-3200 3375);
DISPLAY 1.595745 (-3200 3375);
PAINT GREEN (-3200 3375);
DISPLAY INVISIBLE (-3200 3375);
FORCEPROP 1 LAST BODY_TYPE PLUMBING
J 2
(-2875 3450);
DISPLAY 1.595745 (-2875 3450);
PAINT GREEN (-2875 3450);
DISPLAY INVISIBLE (-2875 3450);
FORCEPROP 2 LAST CDS_LIB mstr_standard
J 0
(-2875 3500);
PAINT MONO (-2875 3500);
DISPLAY INVISIBLE (-2875 3500);
FORCEADD TAP..6
R 2
(-2875 3650);
FORCEPROP 3 LASTPIN (-2925 3650) SIG_NAME M_M_DQS_DN<16>
J 0
(-2915 3660);
DISPLAY 0.659574 (-2915 3660);
PAINT MONO (-2915 3660);
DISPLAY INVISIBLE (-2915 3660);
FORCEPROP 1 LASTPIN (-2925 3650) BN 16
J 2
(-2873 3658);
DISPLAY 0.617021 (-2873 3658);
PAINT GREEN (-2873 3658);
FORCEPROP 1 LAST PATH I141
J 2
(-2873 3650);
DISPLAY 0.872340 (-2873 3650);
PAINT GREEN (-2873 3650);
DISPLAY INVISIBLE (-2873 3650);
FORCEPROP 1 LAST HDL_TAP TRUE
J 2
(-3200 3525);
DISPLAY 1.595745 (-3200 3525);
PAINT GREEN (-3200 3525);
DISPLAY INVISIBLE (-3200 3525);
FORCEPROP 1 LAST BODY_TYPE PLUMBING
J 2
(-2875 3600);
DISPLAY 1.595745 (-2875 3600);
PAINT GREEN (-2875 3600);
DISPLAY INVISIBLE (-2875 3600);
FORCEPROP 2 LAST CDS_LIB mstr_standard
J 0
(-2875 3650);
PAINT MONO (-2875 3650);
DISPLAY INVISIBLE (-2875 3650);
FORCEADD TAP..6
R 2
(-2875 3700);
FORCEPROP 3 LASTPIN (-2925 3700) SIG_NAME M_M_DQS_DN<17>
J 0
(-2915 3710);
DISPLAY 0.659574 (-2915 3710);
PAINT MONO (-2915 3710);
DISPLAY INVISIBLE (-2915 3710);
FORCEPROP 1 LASTPIN (-2925 3700) BN 17
J 2
(-2873 3708);
DISPLAY 0.617021 (-2873 3708);
PAINT GREEN (-2873 3708);
FORCEPROP 1 LAST PATH I142
J 2
(-2873 3700);
DISPLAY 0.872340 (-2873 3700);
PAINT GREEN (-2873 3700);
DISPLAY INVISIBLE (-2873 3700);
FORCEPROP 1 LAST HDL_TAP TRUE
J 2
(-3200 3575);
DISPLAY 1.595745 (-3200 3575);
PAINT GREEN (-3200 3575);
DISPLAY INVISIBLE (-3200 3575);
FORCEPROP 1 LAST BODY_TYPE PLUMBING
J 2
(-2875 3650);
DISPLAY 1.595745 (-2875 3650);
PAINT GREEN (-2875 3650);
DISPLAY INVISIBLE (-2875 3650);
FORCEPROP 2 LAST CDS_LIB mstr_standard
J 0
(-2875 3700);
PAINT MONO (-2875 3700);
DISPLAY INVISIBLE (-2875 3700);
FORCEADD TAP..6
R 2
(-2875 3800);
FORCEPROP 3 LASTPIN (-2925 3800) SIG_NAME M_M_DQS_DP<0>
J 0
(-2915 3810);
DISPLAY 0.659574 (-2915 3810);
PAINT MONO (-2915 3810);
DISPLAY INVISIBLE (-2915 3810);
FORCEPROP 1 LASTPIN (-2925 3800) BN 0
J 2
(-2873 3808);
DISPLAY 0.617021 (-2873 3808);
PAINT GREEN (-2873 3808);
FORCEPROP 1 LAST PATH I143
J 2
(-2873 3800);
DISPLAY 0.872340 (-2873 3800);
PAINT GREEN (-2873 3800);
DISPLAY INVISIBLE (-2873 3800);
FORCEPROP 1 LAST HDL_TAP TRUE
J 2
(-3200 3675);
DISPLAY 1.595745 (-3200 3675);
PAINT GREEN (-3200 3675);
DISPLAY INVISIBLE (-3200 3675);
FORCEPROP 1 LAST BODY_TYPE PLUMBING
J 2
(-2875 3750);
DISPLAY 1.595745 (-2875 3750);
PAINT GREEN (-2875 3750);
DISPLAY INVISIBLE (-2875 3750);
FORCEPROP 2 LAST CDS_LIB mstr_standard
J 0
(-2875 3800);
PAINT MONO (-2875 3800);
DISPLAY INVISIBLE (-2875 3800);
FORCEADD TAP..6
R 2
(-2875 3850);
FORCEPROP 3 LASTPIN (-2925 3850) SIG_NAME M_M_DQS_DP<1>
J 0
(-2915 3860);
DISPLAY 0.659574 (-2915 3860);
PAINT MONO (-2915 3860);
DISPLAY INVISIBLE (-2915 3860);
FORCEPROP 1 LASTPIN (-2925 3850) BN 1
J 2
(-2873 3858);
DISPLAY 0.617021 (-2873 3858);
PAINT GREEN (-2873 3858);
FORCEPROP 1 LAST PATH I144
J 2
(-2873 3850);
DISPLAY 0.872340 (-2873 3850);
PAINT GREEN (-2873 3850);
DISPLAY INVISIBLE (-2873 3850);
FORCEPROP 1 LAST HDL_TAP TRUE
J 2
(-3200 3725);
DISPLAY 1.595745 (-3200 3725);
PAINT GREEN (-3200 3725);
DISPLAY INVISIBLE (-3200 3725);
FORCEPROP 1 LAST BODY_TYPE PLUMBING
J 2
(-2875 3800);
DISPLAY 1.595745 (-2875 3800);
PAINT GREEN (-2875 3800);
DISPLAY INVISIBLE (-2875 3800);
FORCEPROP 2 LAST CDS_LIB mstr_standard
J 0
(-2875 3850);
PAINT MONO (-2875 3850);
DISPLAY INVISIBLE (-2875 3850);
FORCEADD TAP..6
R 2
(-2875 3900);
FORCEPROP 3 LASTPIN (-2925 3900) SIG_NAME M_M_DQS_DP<2>
J 0
(-2915 3910);
DISPLAY 0.659574 (-2915 3910);
PAINT MONO (-2915 3910);
DISPLAY INVISIBLE (-2915 3910);
FORCEPROP 1 LASTPIN (-2925 3900) BN 2
J 2
(-2873 3908);
DISPLAY 0.617021 (-2873 3908);
PAINT GREEN (-2873 3908);
FORCEPROP 1 LAST PATH I145
J 2
(-2873 3900);
DISPLAY 0.872340 (-2873 3900);
PAINT GREEN (-2873 3900);
DISPLAY INVISIBLE (-2873 3900);
FORCEPROP 1 LAST HDL_TAP TRUE
J 2
(-3200 3775);
DISPLAY 1.595745 (-3200 3775);
PAINT GREEN (-3200 3775);
DISPLAY INVISIBLE (-3200 3775);
FORCEPROP 1 LAST BODY_TYPE PLUMBING
J 2
(-2875 3850);
DISPLAY 1.595745 (-2875 3850);
PAINT GREEN (-2875 3850);
DISPLAY INVISIBLE (-2875 3850);
FORCEPROP 2 LAST CDS_LIB mstr_standard
J 0
(-2875 3900);
PAINT MONO (-2875 3900);
DISPLAY INVISIBLE (-2875 3900);
FORCEADD TAP..6
R 2
(-2875 3950);
FORCEPROP 3 LASTPIN (-2925 3950) SIG_NAME M_M_DQS_DP<3>
J 0
(-2915 3960);
DISPLAY 0.659574 (-2915 3960);
PAINT MONO (-2915 3960);
DISPLAY INVISIBLE (-2915 3960);
FORCEPROP 1 LASTPIN (-2925 3950) BN 3
J 2
(-2873 3958);
DISPLAY 0.617021 (-2873 3958);
PAINT GREEN (-2873 3958);
FORCEPROP 1 LAST PATH I146
J 2
(-2873 3950);
DISPLAY 0.872340 (-2873 3950);
PAINT GREEN (-2873 3950);
DISPLAY INVISIBLE (-2873 3950);
FORCEPROP 1 LAST HDL_TAP TRUE
J 2
(-3200 3825);
DISPLAY 1.595745 (-3200 3825);
PAINT GREEN (-3200 3825);
DISPLAY INVISIBLE (-3200 3825);
FORCEPROP 1 LAST BODY_TYPE PLUMBING
J 2
(-2875 3900);
DISPLAY 1.595745 (-2875 3900);
PAINT GREEN (-2875 3900);
DISPLAY INVISIBLE (-2875 3900);
FORCEPROP 2 LAST CDS_LIB mstr_standard
J 0
(-2875 3950);
PAINT MONO (-2875 3950);
DISPLAY INVISIBLE (-2875 3950);
FORCEADD OFFPAGE..2
(-2025 500);
FORCEPROP 2 LAST $XR1 88 
J 0
(-1746 500);
DISPLAY 0.638298 (-1746 500);
PAINT MONO (-1746 500);
FORCEPROP 2 LAST $XR0 87 
J 0
(-1836 500);
DISPLAY 0.638298 (-1836 500);
PAINT MONO (-1836 500);
FORCEPROP 2 LAST PATH I147
J 0
(-1850 575);
DISPLAY 1.021277 (-1850 575);
PAINT ORANGE (-1850 575);
DISPLAY INVISIBLE (-1850 575);
FORCEPROP 1 LAST COMMENT_BODY TRUE
J 0
(-2070 405);
DISPLAY 1.170213 (-2070 405);
PAINT GREEN (-2070 405);
DISPLAY INVISIBLE (-2070 405);
FORCEPROP 1 LAST OFFPAGE TRUE
J 0
(-1700 375);
DISPLAY 1.170213 (-1700 375);
PAINT GREEN (-1700 375);
DISPLAY INVISIBLE (-1700 375);
FORCEPROP 2 LAST CDS_LIB mstr_standard
J 0
(-2025 500);
PAINT MONO (-2025 500);
DISPLAY INVISIBLE (-2025 500);
FORCEADD OFFPAGE..2
(-2025 600);
FORCEPROP 2 LAST $XR1 88 
J 0
(-1746 600);
DISPLAY 0.638298 (-1746 600);
PAINT MONO (-1746 600);
FORCEPROP 2 LAST $XR0 87 
J 0
(-1836 600);
DISPLAY 0.638298 (-1836 600);
PAINT MONO (-1836 600);
FORCEPROP 2 LAST PATH I148
J 0
(-1850 675);
DISPLAY 1.021277 (-1850 675);
PAINT ORANGE (-1850 675);
DISPLAY INVISIBLE (-1850 675);
FORCEPROP 1 LAST COMMENT_BODY TRUE
J 0
(-2070 505);
DISPLAY 1.170213 (-2070 505);
PAINT GREEN (-2070 505);
DISPLAY INVISIBLE (-2070 505);
FORCEPROP 1 LAST OFFPAGE TRUE
J 0
(-1700 475);
DISPLAY 1.170213 (-1700 475);
PAINT GREEN (-1700 475);
DISPLAY INVISIBLE (-1700 475);
FORCEPROP 2 LAST CDS_LIB mstr_standard
J 0
(-2025 600);
PAINT MONO (-2025 600);
DISPLAY INVISIBLE (-2025 600);
FORCEADD OFFPAGE..4
(-2025 550);
FORCEPROP 2 LAST $XR1 88 
J 0
(-1749 550);
DISPLAY 0.638298 (-1749 550);
PAINT MONO (-1749 550);
FORCEPROP 2 LAST $XR0 87 
J 0
(-1839 550);
DISPLAY 0.638298 (-1839 550);
PAINT MONO (-1839 550);
FORCEPROP 2 LAST PATH I149
J 0
(-1850 625);
DISPLAY 1.021277 (-1850 625);
PAINT ORANGE (-1850 625);
DISPLAY INVISIBLE (-1850 625);
FORCEPROP 1 LAST COMMENT_BODY TRUE
J 0
(-2050 450);
DISPLAY 1.170213 (-2050 450);
PAINT GREEN (-2050 450);
DISPLAY INVISIBLE (-2050 450);
FORCEPROP 1 LAST OFFPAGE TRUE
J 0
(-1700 425);
DISPLAY 1.170213 (-1700 425);
PAINT GREEN (-1700 425);
DISPLAY INVISIBLE (-1700 425);
FORCEPROP 2 LAST CDS_LIB mstr_standard
J 0
(-2025 550);
PAINT MONO (-2025 550);
DISPLAY INVISIBLE (-2025 550);
FORCEADD TAP..6
(-5600 1150);
FORCEPROP 3 LASTPIN (-5550 1150) SIG_NAME M_M_ECC<2>
J 0
(-5540 1160);
DISPLAY 0.659574 (-5540 1160);
PAINT MONO (-5540 1160);
DISPLAY INVISIBLE (-5540 1160);
FORCEPROP 1 LASTPIN (-5550 1150) BN 2
J 0
(-5602 1158);
DISPLAY 0.617021 (-5602 1158);
PAINT GREEN (-5602 1158);
FORCEPROP 1 LAST PATH I15
J 0
(-5602 1150);
DISPLAY 0.872340 (-5602 1150);
PAINT GREEN (-5602 1150);
DISPLAY INVISIBLE (-5602 1150);
FORCEPROP 1 LAST HDL_TAP TRUE
J 0
(-5275 1025);
DISPLAY 1.595745 (-5275 1025);
PAINT GREEN (-5275 1025);
DISPLAY INVISIBLE (-5275 1025);
FORCEPROP 1 LAST BODY_TYPE PLUMBING
J 0
(-5600 1100);
DISPLAY 1.595745 (-5600 1100);
PAINT GREEN (-5600 1100);
DISPLAY INVISIBLE (-5600 1100);
FORCEPROP 2 LAST CDS_LIB mstr_standard
J 0
(-5600 1150);
PAINT MONO (-5600 1150);
DISPLAY INVISIBLE (-5600 1150);
FORCEADD OFFPAGE..2
(-2025 800);
FORCEPROP 2 LAST $XR1 88 
J 0
(-1746 800);
DISPLAY 0.638298 (-1746 800);
PAINT MONO (-1746 800);
FORCEPROP 2 LAST $XR0 87 
J 0
(-1836 800);
DISPLAY 0.638298 (-1836 800);
PAINT MONO (-1836 800);
FORCEPROP 2 LAST PATH I150
J 0
(-1850 875);
DISPLAY 1.021277 (-1850 875);
PAINT ORANGE (-1850 875);
DISPLAY INVISIBLE (-1850 875);
FORCEPROP 1 LAST COMMENT_BODY TRUE
J 0
(-2070 705);
DISPLAY 1.170213 (-2070 705);
PAINT GREEN (-2070 705);
DISPLAY INVISIBLE (-2070 705);
FORCEPROP 1 LAST OFFPAGE TRUE
J 0
(-1700 675);
DISPLAY 1.170213 (-1700 675);
PAINT GREEN (-1700 675);
DISPLAY INVISIBLE (-1700 675);
FORCEPROP 2 LAST CDS_LIB mstr_standard
J 0
(-2025 800);
PAINT MONO (-2025 800);
DISPLAY INVISIBLE (-2025 800);
FORCEADD OFFPAGE..2
(-2025 900);
FORCEPROP 2 LAST $XR1 88 
J 0
(-1746 900);
DISPLAY 0.638298 (-1746 900);
PAINT MONO (-1746 900);
FORCEPROP 2 LAST $XR0 87 
J 0
(-1836 900);
DISPLAY 0.638298 (-1836 900);
PAINT MONO (-1836 900);
FORCEPROP 2 LAST PATH I151
J 0
(-1850 975);
DISPLAY 1.021277 (-1850 975);
PAINT ORANGE (-1850 975);
DISPLAY INVISIBLE (-1850 975);
FORCEPROP 1 LAST COMMENT_BODY TRUE
J 0
(-2070 805);
DISPLAY 1.170213 (-2070 805);
PAINT GREEN (-2070 805);
DISPLAY INVISIBLE (-2070 805);
FORCEPROP 1 LAST OFFPAGE TRUE
J 0
(-1700 775);
DISPLAY 1.170213 (-1700 775);
PAINT GREEN (-1700 775);
DISPLAY INVISIBLE (-1700 775);
FORCEPROP 2 LAST CDS_LIB mstr_standard
J 0
(-2025 900);
PAINT MONO (-2025 900);
DISPLAY INVISIBLE (-2025 900);
FORCEADD OFFPAGE..2
(-2025 1350);
FORCEPROP 2 LAST $XR1 88 
J 0
(-1746 1350);
DISPLAY 0.638298 (-1746 1350);
PAINT MONO (-1746 1350);
FORCEPROP 2 LAST $XR0 87 
J 0
(-1836 1350);
DISPLAY 0.638298 (-1836 1350);
PAINT MONO (-1836 1350);
FORCEPROP 2 LAST PATH I152
J 0
(-1850 1425);
DISPLAY 1.021277 (-1850 1425);
PAINT ORANGE (-1850 1425);
DISPLAY INVISIBLE (-1850 1425);
FORCEPROP 1 LAST COMMENT_BODY TRUE
J 0
(-2070 1255);
DISPLAY 1.170213 (-2070 1255);
PAINT GREEN (-2070 1255);
DISPLAY INVISIBLE (-2070 1255);
FORCEPROP 1 LAST OFFPAGE TRUE
J 0
(-1700 1225);
DISPLAY 1.170213 (-1700 1225);
PAINT GREEN (-1700 1225);
DISPLAY INVISIBLE (-1700 1225);
FORCEPROP 2 LAST CDS_LIB mstr_standard
J 0
(-2025 1350);
PAINT MONO (-2025 1350);
DISPLAY INVISIBLE (-2025 1350);
FORCEADD OFFPAGE..2
(-2025 1600);
FORCEPROP 2 LAST $XR1 88 
J 0
(-1746 1600);
DISPLAY 0.638298 (-1746 1600);
PAINT MONO (-1746 1600);
FORCEPROP 2 LAST $XR0 87 
J 0
(-1836 1600);
DISPLAY 0.638298 (-1836 1600);
PAINT MONO (-1836 1600);
FORCEPROP 2 LAST PATH I153
J 0
(-1850 1675);
DISPLAY 1.021277 (-1850 1675);
PAINT ORANGE (-1850 1675);
DISPLAY INVISIBLE (-1850 1675);
FORCEPROP 1 LAST COMMENT_BODY TRUE
J 0
(-2070 1505);
DISPLAY 1.170213 (-2070 1505);
PAINT GREEN (-2070 1505);
DISPLAY INVISIBLE (-2070 1505);
FORCEPROP 1 LAST OFFPAGE TRUE
J 0
(-1700 1475);
DISPLAY 1.170213 (-1700 1475);
PAINT GREEN (-1700 1475);
DISPLAY INVISIBLE (-1700 1475);
FORCEPROP 2 LAST CDS_LIB mstr_standard
J 0
(-2025 1600);
PAINT MONO (-2025 1600);
DISPLAY INVISIBLE (-2025 1600);
FORCEADD OFFPAGE..2
(-2025 1850);
FORCEPROP 2 LAST $XR1 88 
J 0
(-1746 1850);
DISPLAY 0.638298 (-1746 1850);
PAINT MONO (-1746 1850);
FORCEPROP 2 LAST $XR0 87 
J 0
(-1836 1850);
DISPLAY 0.638298 (-1836 1850);
PAINT MONO (-1836 1850);
FORCEPROP 2 LAST PATH I154
J 0
(-1850 1925);
DISPLAY 1.021277 (-1850 1925);
PAINT ORANGE (-1850 1925);
DISPLAY INVISIBLE (-1850 1925);
FORCEPROP 1 LAST COMMENT_BODY TRUE
J 0
(-2070 1755);
DISPLAY 1.170213 (-2070 1755);
PAINT GREEN (-2070 1755);
DISPLAY INVISIBLE (-2070 1755);
FORCEPROP 1 LAST OFFPAGE TRUE
J 0
(-1700 1725);
DISPLAY 1.170213 (-1700 1725);
PAINT GREEN (-1700 1725);
DISPLAY INVISIBLE (-1700 1725);
FORCEPROP 2 LAST CDS_LIB mstr_standard
J 0
(-2025 1850);
PAINT MONO (-2025 1850);
DISPLAY INVISIBLE (-2025 1850);
FORCEADD OFFPAGE..2
(-2025 2800);
FORCEPROP 2 LAST $XR1 88 
J 0
(-1746 2800);
DISPLAY 0.638298 (-1746 2800);
PAINT MONO (-1746 2800);
FORCEPROP 2 LAST $XR0 87 
J 0
(-1836 2800);
DISPLAY 0.638298 (-1836 2800);
PAINT MONO (-1836 2800);
FORCEPROP 2 LAST PATH I155
J 0
(-1850 2875);
DISPLAY 1.021277 (-1850 2875);
PAINT ORANGE (-1850 2875);
DISPLAY INVISIBLE (-1850 2875);
FORCEPROP 1 LAST COMMENT_BODY TRUE
J 0
(-2070 2705);
DISPLAY 1.170213 (-2070 2705);
PAINT GREEN (-2070 2705);
DISPLAY INVISIBLE (-2070 2705);
FORCEPROP 1 LAST OFFPAGE TRUE
J 0
(-1700 2675);
DISPLAY 1.170213 (-1700 2675);
PAINT GREEN (-1700 2675);
DISPLAY INVISIBLE (-1700 2675);
FORCEPROP 2 LAST CDS_LIB mstr_standard
J 0
(-2025 2800);
PAINT MONO (-2025 2800);
DISPLAY INVISIBLE (-2025 2800);
FORCEADD OFFPAGE..3
(-2025 3750);
FORCEPROP 2 LAST $XR1 88 
J 0
(-1721 3750);
DISPLAY 0.638298 (-1721 3750);
PAINT MONO (-1721 3750);
FORCEPROP 2 LAST $XR0 87 
J 0
(-1811 3750);
DISPLAY 0.638298 (-1811 3750);
PAINT MONO (-1811 3750);
FORCEPROP 2 LAST PATH I156
J 0
(-1825 3825);
DISPLAY 1.021277 (-1825 3825);
PAINT ORANGE (-1825 3825);
DISPLAY INVISIBLE (-1825 3825);
FORCEPROP 1 LAST COMMENT_BODY TRUE
J 0
(-2075 3650);
DISPLAY 1.170213 (-2075 3650);
PAINT GREEN (-2075 3650);
DISPLAY INVISIBLE (-2075 3650);
FORCEPROP 1 LAST OFFPAGE TRUE
J 0
(-1700 3625);
DISPLAY 1.170213 (-1700 3625);
PAINT GREEN (-1700 3625);
DISPLAY INVISIBLE (-1700 3625);
FORCEPROP 2 LAST CDS_LIB mstr_standard
J 0
(-2025 3750);
PAINT MONO (-2025 3750);
DISPLAY INVISIBLE (-2025 3750);
FORCEADD TAP..6
R 2
(-2875 4000);
FORCEPROP 3 LASTPIN (-2925 4000) SIG_NAME M_M_DQS_DP<4>
J 0
(-2915 4010);
DISPLAY 0.659574 (-2915 4010);
PAINT MONO (-2915 4010);
DISPLAY INVISIBLE (-2915 4010);
FORCEPROP 1 LASTPIN (-2925 4000) BN 4
J 2
(-2873 4008);
DISPLAY 0.617021 (-2873 4008);
PAINT GREEN (-2873 4008);
FORCEPROP 1 LAST PATH I157
J 2
(-2873 4000);
DISPLAY 0.872340 (-2873 4000);
PAINT GREEN (-2873 4000);
DISPLAY INVISIBLE (-2873 4000);
FORCEPROP 1 LAST HDL_TAP TRUE
J 2
(-3200 3875);
DISPLAY 1.595745 (-3200 3875);
PAINT GREEN (-3200 3875);
DISPLAY INVISIBLE (-3200 3875);
FORCEPROP 1 LAST BODY_TYPE PLUMBING
J 2
(-2875 3950);
DISPLAY 1.595745 (-2875 3950);
PAINT GREEN (-2875 3950);
DISPLAY INVISIBLE (-2875 3950);
FORCEPROP 2 LAST CDS_LIB mstr_standard
J 0
(-2875 4000);
PAINT MONO (-2875 4000);
DISPLAY INVISIBLE (-2875 4000);
FORCEADD TAP..6
R 2
(-2875 4100);
FORCEPROP 3 LASTPIN (-2925 4100) SIG_NAME M_M_DQS_DP<6>
J 0
(-2915 4110);
DISPLAY 0.659574 (-2915 4110);
PAINT MONO (-2915 4110);
DISPLAY INVISIBLE (-2915 4110);
FORCEPROP 1 LASTPIN (-2925 4100) BN 6
J 2
(-2873 4108);
DISPLAY 0.617021 (-2873 4108);
PAINT GREEN (-2873 4108);
FORCEPROP 1 LAST PATH I158
J 2
(-2873 4100);
DISPLAY 0.872340 (-2873 4100);
PAINT GREEN (-2873 4100);
DISPLAY INVISIBLE (-2873 4100);
FORCEPROP 1 LAST HDL_TAP TRUE
J 2
(-3200 3975);
DISPLAY 1.595745 (-3200 3975);
PAINT GREEN (-3200 3975);
DISPLAY INVISIBLE (-3200 3975);
FORCEPROP 1 LAST BODY_TYPE PLUMBING
J 2
(-2875 4050);
DISPLAY 1.595745 (-2875 4050);
PAINT GREEN (-2875 4050);
DISPLAY INVISIBLE (-2875 4050);
FORCEPROP 2 LAST CDS_LIB mstr_standard
J 0
(-2875 4100);
PAINT MONO (-2875 4100);
DISPLAY INVISIBLE (-2875 4100);
FORCEADD TAP..6
R 2
(-2875 4050);
FORCEPROP 3 LASTPIN (-2925 4050) SIG_NAME M_M_DQS_DP<5>
J 0
(-2915 4060);
DISPLAY 0.659574 (-2915 4060);
PAINT MONO (-2915 4060);
DISPLAY INVISIBLE (-2915 4060);
FORCEPROP 1 LASTPIN (-2925 4050) BN 5
J 2
(-2873 4058);
DISPLAY 0.617021 (-2873 4058);
PAINT GREEN (-2873 4058);
FORCEPROP 1 LAST PATH I159
J 2
(-2873 4050);
DISPLAY 0.872340 (-2873 4050);
PAINT GREEN (-2873 4050);
DISPLAY INVISIBLE (-2873 4050);
FORCEPROP 1 LAST HDL_TAP TRUE
J 2
(-3200 3925);
DISPLAY 1.595745 (-3200 3925);
PAINT GREEN (-3200 3925);
DISPLAY INVISIBLE (-3200 3925);
FORCEPROP 1 LAST BODY_TYPE PLUMBING
J 2
(-2875 4000);
DISPLAY 1.595745 (-2875 4000);
PAINT GREEN (-2875 4000);
DISPLAY INVISIBLE (-2875 4000);
FORCEPROP 2 LAST CDS_LIB mstr_standard
J 0
(-2875 4050);
PAINT MONO (-2875 4050);
DISPLAY INVISIBLE (-2875 4050);
FORCEADD TAP..6
(-5600 1250);
FORCEPROP 3 LASTPIN (-5550 1250) SIG_NAME M_M_ECC<4>
J 0
(-5540 1260);
DISPLAY 0.659574 (-5540 1260);
PAINT MONO (-5540 1260);
DISPLAY INVISIBLE (-5540 1260);
FORCEPROP 1 LASTPIN (-5550 1250) BN 4
J 0
(-5602 1258);
DISPLAY 0.617021 (-5602 1258);
PAINT GREEN (-5602 1258);
FORCEPROP 1 LAST PATH I16
J 0
(-5602 1250);
DISPLAY 0.872340 (-5602 1250);
PAINT GREEN (-5602 1250);
DISPLAY INVISIBLE (-5602 1250);
FORCEPROP 1 LAST HDL_TAP TRUE
J 0
(-5275 1125);
DISPLAY 1.595745 (-5275 1125);
PAINT GREEN (-5275 1125);
DISPLAY INVISIBLE (-5275 1125);
FORCEPROP 1 LAST BODY_TYPE PLUMBING
J 0
(-5600 1200);
DISPLAY 1.595745 (-5600 1200);
PAINT GREEN (-5600 1200);
DISPLAY INVISIBLE (-5600 1200);
FORCEPROP 2 LAST CDS_LIB mstr_standard
J 0
(-5600 1250);
PAINT MONO (-5600 1250);
DISPLAY INVISIBLE (-5600 1250);
FORCEADD TAP..6
R 2
(-2875 4150);
FORCEPROP 3 LASTPIN (-2925 4150) SIG_NAME M_M_DQS_DP<7>
J 0
(-2915 4160);
DISPLAY 0.659574 (-2915 4160);
PAINT MONO (-2915 4160);
DISPLAY INVISIBLE (-2915 4160);
FORCEPROP 1 LASTPIN (-2925 4150) BN 7
J 2
(-2873 4158);
DISPLAY 0.617021 (-2873 4158);
PAINT GREEN (-2873 4158);
FORCEPROP 1 LAST PATH I160
J 2
(-2873 4150);
DISPLAY 0.872340 (-2873 4150);
PAINT GREEN (-2873 4150);
DISPLAY INVISIBLE (-2873 4150);
FORCEPROP 1 LAST HDL_TAP TRUE
J 2
(-3200 4025);
DISPLAY 1.595745 (-3200 4025);
PAINT GREEN (-3200 4025);
DISPLAY INVISIBLE (-3200 4025);
FORCEPROP 1 LAST BODY_TYPE PLUMBING
J 2
(-2875 4100);
DISPLAY 1.595745 (-2875 4100);
PAINT GREEN (-2875 4100);
DISPLAY INVISIBLE (-2875 4100);
FORCEPROP 2 LAST CDS_LIB mstr_standard
J 0
(-2875 4150);
PAINT MONO (-2875 4150);
DISPLAY INVISIBLE (-2875 4150);
FORCEADD TAP..6
R 2
(-2875 4200);
FORCEPROP 3 LASTPIN (-2925 4200) SIG_NAME M_M_DQS_DP<8>
J 0
(-2915 4210);
DISPLAY 0.659574 (-2915 4210);
PAINT MONO (-2915 4210);
DISPLAY INVISIBLE (-2915 4210);
FORCEPROP 1 LASTPIN (-2925 4200) BN 8
J 2
(-2873 4208);
DISPLAY 0.617021 (-2873 4208);
PAINT GREEN (-2873 4208);
FORCEPROP 1 LAST PATH I161
J 2
(-2873 4200);
DISPLAY 0.872340 (-2873 4200);
PAINT GREEN (-2873 4200);
DISPLAY INVISIBLE (-2873 4200);
FORCEPROP 1 LAST HDL_TAP TRUE
J 2
(-3200 4075);
DISPLAY 1.595745 (-3200 4075);
PAINT GREEN (-3200 4075);
DISPLAY INVISIBLE (-3200 4075);
FORCEPROP 1 LAST BODY_TYPE PLUMBING
J 2
(-2875 4150);
DISPLAY 1.595745 (-2875 4150);
PAINT GREEN (-2875 4150);
DISPLAY INVISIBLE (-2875 4150);
FORCEPROP 2 LAST CDS_LIB mstr_standard
J 0
(-2875 4200);
PAINT MONO (-2875 4200);
DISPLAY INVISIBLE (-2875 4200);
FORCEADD TAP..6
R 2
(-2875 4250);
FORCEPROP 3 LASTPIN (-2925 4250) SIG_NAME M_M_DQS_DP<9>
J 0
(-2915 4260);
DISPLAY 0.659574 (-2915 4260);
PAINT MONO (-2915 4260);
DISPLAY INVISIBLE (-2915 4260);
FORCEPROP 1 LASTPIN (-2925 4250) BN 9
J 2
(-2873 4258);
DISPLAY 0.617021 (-2873 4258);
PAINT GREEN (-2873 4258);
FORCEPROP 1 LAST PATH I162
J 2
(-2873 4250);
DISPLAY 0.872340 (-2873 4250);
PAINT GREEN (-2873 4250);
DISPLAY INVISIBLE (-2873 4250);
FORCEPROP 1 LAST HDL_TAP TRUE
J 2
(-3200 4125);
DISPLAY 1.595745 (-3200 4125);
PAINT GREEN (-3200 4125);
DISPLAY INVISIBLE (-3200 4125);
FORCEPROP 1 LAST BODY_TYPE PLUMBING
J 2
(-2875 4200);
DISPLAY 1.595745 (-2875 4200);
PAINT GREEN (-2875 4200);
DISPLAY INVISIBLE (-2875 4200);
FORCEPROP 2 LAST CDS_LIB mstr_standard
J 0
(-2875 4250);
PAINT MONO (-2875 4250);
DISPLAY INVISIBLE (-2875 4250);
FORCEADD TAP..6
R 2
(-2875 4300);
FORCEPROP 3 LASTPIN (-2925 4300) SIG_NAME M_M_DQS_DP<10>
J 0
(-2915 4310);
DISPLAY 0.659574 (-2915 4310);
PAINT MONO (-2915 4310);
DISPLAY INVISIBLE (-2915 4310);
FORCEPROP 1 LASTPIN (-2925 4300) BN 10
J 2
(-2873 4308);
DISPLAY 0.617021 (-2873 4308);
PAINT GREEN (-2873 4308);
FORCEPROP 1 LAST PATH I163
J 2
(-2873 4300);
DISPLAY 0.872340 (-2873 4300);
PAINT GREEN (-2873 4300);
DISPLAY INVISIBLE (-2873 4300);
FORCEPROP 1 LAST HDL_TAP TRUE
J 2
(-3200 4175);
DISPLAY 1.595745 (-3200 4175);
PAINT GREEN (-3200 4175);
DISPLAY INVISIBLE (-3200 4175);
FORCEPROP 1 LAST BODY_TYPE PLUMBING
J 2
(-2875 4250);
DISPLAY 1.595745 (-2875 4250);
PAINT GREEN (-2875 4250);
DISPLAY INVISIBLE (-2875 4250);
FORCEPROP 2 LAST CDS_LIB mstr_standard
J 0
(-2875 4300);
PAINT MONO (-2875 4300);
DISPLAY INVISIBLE (-2875 4300);
FORCEADD TAP..6
R 2
(-2875 4350);
FORCEPROP 3 LASTPIN (-2925 4350) SIG_NAME M_M_DQS_DP<11>
J 0
(-2915 4360);
DISPLAY 0.659574 (-2915 4360);
PAINT MONO (-2915 4360);
DISPLAY INVISIBLE (-2915 4360);
FORCEPROP 1 LASTPIN (-2925 4350) BN 11
J 2
(-2873 4358);
DISPLAY 0.617021 (-2873 4358);
PAINT GREEN (-2873 4358);
FORCEPROP 1 LAST PATH I164
J 2
(-2873 4350);
DISPLAY 0.872340 (-2873 4350);
PAINT GREEN (-2873 4350);
DISPLAY INVISIBLE (-2873 4350);
FORCEPROP 1 LAST HDL_TAP TRUE
J 2
(-3200 4225);
DISPLAY 1.595745 (-3200 4225);
PAINT GREEN (-3200 4225);
DISPLAY INVISIBLE (-3200 4225);
FORCEPROP 1 LAST BODY_TYPE PLUMBING
J 2
(-2875 4300);
DISPLAY 1.595745 (-2875 4300);
PAINT GREEN (-2875 4300);
DISPLAY INVISIBLE (-2875 4300);
FORCEPROP 2 LAST CDS_LIB mstr_standard
J 0
(-2875 4350);
PAINT MONO (-2875 4350);
DISPLAY INVISIBLE (-2875 4350);
FORCEADD TAP..6
R 2
(-2875 4500);
FORCEPROP 3 LASTPIN (-2925 4500) SIG_NAME M_M_DQS_DP<14>
J 0
(-2915 4510);
DISPLAY 0.659574 (-2915 4510);
PAINT MONO (-2915 4510);
DISPLAY INVISIBLE (-2915 4510);
FORCEPROP 1 LASTPIN (-2925 4500) BN 14
J 2
(-2873 4508);
DISPLAY 0.617021 (-2873 4508);
PAINT GREEN (-2873 4508);
FORCEPROP 1 LAST PATH I165
J 2
(-2873 4500);
DISPLAY 0.872340 (-2873 4500);
PAINT GREEN (-2873 4500);
DISPLAY INVISIBLE (-2873 4500);
FORCEPROP 1 LAST HDL_TAP TRUE
J 2
(-3200 4375);
DISPLAY 1.595745 (-3200 4375);
PAINT GREEN (-3200 4375);
DISPLAY INVISIBLE (-3200 4375);
FORCEPROP 1 LAST BODY_TYPE PLUMBING
J 2
(-2875 4450);
DISPLAY 1.595745 (-2875 4450);
PAINT GREEN (-2875 4450);
DISPLAY INVISIBLE (-2875 4450);
FORCEPROP 2 LAST CDS_LIB mstr_standard
J 0
(-2875 4500);
PAINT MONO (-2875 4500);
DISPLAY INVISIBLE (-2875 4500);
FORCEADD TAP..6
R 2
(-2875 4450);
FORCEPROP 3 LASTPIN (-2925 4450) SIG_NAME M_M_DQS_DP<13>
J 0
(-2915 4460);
DISPLAY 0.659574 (-2915 4460);
PAINT MONO (-2915 4460);
DISPLAY INVISIBLE (-2915 4460);
FORCEPROP 1 LASTPIN (-2925 4450) BN 13
J 2
(-2873 4458);
DISPLAY 0.617021 (-2873 4458);
PAINT GREEN (-2873 4458);
FORCEPROP 1 LAST PATH I166
J 2
(-2873 4450);
DISPLAY 0.872340 (-2873 4450);
PAINT GREEN (-2873 4450);
DISPLAY INVISIBLE (-2873 4450);
FORCEPROP 1 LAST HDL_TAP TRUE
J 2
(-3200 4325);
DISPLAY 1.595745 (-3200 4325);
PAINT GREEN (-3200 4325);
DISPLAY INVISIBLE (-3200 4325);
FORCEPROP 1 LAST BODY_TYPE PLUMBING
J 2
(-2875 4400);
DISPLAY 1.595745 (-2875 4400);
PAINT GREEN (-2875 4400);
DISPLAY INVISIBLE (-2875 4400);
FORCEPROP 2 LAST CDS_LIB mstr_standard
J 0
(-2875 4450);
PAINT MONO (-2875 4450);
DISPLAY INVISIBLE (-2875 4450);
FORCEADD TAP..6
R 2
(-2875 4400);
FORCEPROP 3 LASTPIN (-2925 4400) SIG_NAME M_M_DQS_DP<12>
J 0
(-2915 4410);
DISPLAY 0.659574 (-2915 4410);
PAINT MONO (-2915 4410);
DISPLAY INVISIBLE (-2915 4410);
FORCEPROP 1 LASTPIN (-2925 4400) BN 12
J 2
(-2873 4408);
DISPLAY 0.617021 (-2873 4408);
PAINT GREEN (-2873 4408);
FORCEPROP 1 LAST PATH I167
J 2
(-2873 4400);
DISPLAY 0.872340 (-2873 4400);
PAINT GREEN (-2873 4400);
DISPLAY INVISIBLE (-2873 4400);
FORCEPROP 1 LAST HDL_TAP TRUE
J 2
(-3200 4275);
DISPLAY 1.595745 (-3200 4275);
PAINT GREEN (-3200 4275);
DISPLAY INVISIBLE (-3200 4275);
FORCEPROP 1 LAST BODY_TYPE PLUMBING
J 2
(-2875 4350);
DISPLAY 1.595745 (-2875 4350);
PAINT GREEN (-2875 4350);
DISPLAY INVISIBLE (-2875 4350);
FORCEPROP 2 LAST CDS_LIB mstr_standard
J 0
(-2875 4400);
PAINT MONO (-2875 4400);
DISPLAY INVISIBLE (-2875 4400);
FORCEADD TAP..6
R 2
(-2875 4550);
FORCEPROP 3 LASTPIN (-2925 4550) SIG_NAME M_M_DQS_DP<15>
J 0
(-2915 4560);
DISPLAY 0.659574 (-2915 4560);
PAINT MONO (-2915 4560);
DISPLAY INVISIBLE (-2915 4560);
FORCEPROP 1 LASTPIN (-2925 4550) BN 15
J 2
(-2873 4558);
DISPLAY 0.617021 (-2873 4558);
PAINT GREEN (-2873 4558);
FORCEPROP 1 LAST PATH I168
J 2
(-2873 4550);
DISPLAY 0.872340 (-2873 4550);
PAINT GREEN (-2873 4550);
DISPLAY INVISIBLE (-2873 4550);
FORCEPROP 1 LAST HDL_TAP TRUE
J 2
(-3200 4425);
DISPLAY 1.595745 (-3200 4425);
PAINT GREEN (-3200 4425);
DISPLAY INVISIBLE (-3200 4425);
FORCEPROP 1 LAST BODY_TYPE PLUMBING
J 2
(-2875 4500);
DISPLAY 1.595745 (-2875 4500);
PAINT GREEN (-2875 4500);
DISPLAY INVISIBLE (-2875 4500);
FORCEPROP 2 LAST CDS_LIB mstr_standard
J 0
(-2875 4550);
PAINT MONO (-2875 4550);
DISPLAY INVISIBLE (-2875 4550);
FORCEADD TAP..6
R 2
(-2875 4600);
FORCEPROP 3 LASTPIN (-2925 4600) SIG_NAME M_M_DQS_DP<16>
J 0
(-2915 4610);
DISPLAY 0.659574 (-2915 4610);
PAINT MONO (-2915 4610);
DISPLAY INVISIBLE (-2915 4610);
FORCEPROP 1 LASTPIN (-2925 4600) BN 16
J 2
(-2873 4608);
DISPLAY 0.617021 (-2873 4608);
PAINT GREEN (-2873 4608);
FORCEPROP 1 LAST PATH I169
J 2
(-2873 4600);
DISPLAY 0.872340 (-2873 4600);
PAINT GREEN (-2873 4600);
DISPLAY INVISIBLE (-2873 4600);
FORCEPROP 1 LAST HDL_TAP TRUE
J 2
(-3200 4475);
DISPLAY 1.595745 (-3200 4475);
PAINT GREEN (-3200 4475);
DISPLAY INVISIBLE (-3200 4475);
FORCEPROP 1 LAST BODY_TYPE PLUMBING
J 2
(-2875 4550);
DISPLAY 1.595745 (-2875 4550);
PAINT GREEN (-2875 4550);
DISPLAY INVISIBLE (-2875 4550);
FORCEPROP 2 LAST CDS_LIB mstr_standard
J 0
(-2875 4600);
PAINT MONO (-2875 4600);
DISPLAY INVISIBLE (-2875 4600);
FORCEADD TAP..6
(-5600 1200);
FORCEPROP 3 LASTPIN (-5550 1200) SIG_NAME M_M_ECC<3>
J 0
(-5540 1210);
DISPLAY 0.659574 (-5540 1210);
PAINT MONO (-5540 1210);
DISPLAY INVISIBLE (-5540 1210);
FORCEPROP 1 LASTPIN (-5550 1200) BN 3
J 0
(-5602 1208);
DISPLAY 0.617021 (-5602 1208);
PAINT GREEN (-5602 1208);
FORCEPROP 1 LAST PATH I17
J 0
(-5602 1200);
DISPLAY 0.872340 (-5602 1200);
PAINT GREEN (-5602 1200);
DISPLAY INVISIBLE (-5602 1200);
FORCEPROP 1 LAST HDL_TAP TRUE
J 0
(-5275 1075);
DISPLAY 1.595745 (-5275 1075);
PAINT GREEN (-5275 1075);
DISPLAY INVISIBLE (-5275 1075);
FORCEPROP 1 LAST BODY_TYPE PLUMBING
J 0
(-5600 1150);
DISPLAY 1.595745 (-5600 1150);
PAINT GREEN (-5600 1150);
DISPLAY INVISIBLE (-5600 1150);
FORCEPROP 2 LAST CDS_LIB mstr_standard
J 0
(-5600 1200);
PAINT MONO (-5600 1200);
DISPLAY INVISIBLE (-5600 1200);
FORCEADD TAP..6
R 2
(-2875 4650);
FORCEPROP 3 LASTPIN (-2925 4650) SIG_NAME M_M_DQS_DP<17>
J 0
(-2915 4660);
DISPLAY 0.659574 (-2915 4660);
PAINT MONO (-2915 4660);
DISPLAY INVISIBLE (-2915 4660);
FORCEPROP 1 LASTPIN (-2925 4650) BN 17
J 2
(-2873 4658);
DISPLAY 0.617021 (-2873 4658);
PAINT GREEN (-2873 4658);
FORCEPROP 1 LAST PATH I170
J 2
(-2873 4650);
DISPLAY 0.872340 (-2873 4650);
PAINT GREEN (-2873 4650);
DISPLAY INVISIBLE (-2873 4650);
FORCEPROP 1 LAST HDL_TAP TRUE
J 2
(-3200 4525);
DISPLAY 1.595745 (-3200 4525);
PAINT GREEN (-3200 4525);
DISPLAY INVISIBLE (-3200 4525);
FORCEPROP 1 LAST BODY_TYPE PLUMBING
J 2
(-2875 4600);
DISPLAY 1.595745 (-2875 4600);
PAINT GREEN (-2875 4600);
DISPLAY INVISIBLE (-2875 4600);
FORCEPROP 2 LAST CDS_LIB mstr_standard
J 2
(-2875 4650);
PAINT MONO (-2875 4650);
DISPLAY INVISIBLE (-2875 4650);
FORCEADD OFFPAGE..3
(-2025 4725);
FORCEPROP 2 LAST $XR1 88 
J 0
(-1721 4725);
DISPLAY 0.638298 (-1721 4725);
PAINT MONO (-1721 4725);
FORCEPROP 2 LAST $XR0 87 
J 0
(-1811 4725);
DISPLAY 0.638298 (-1811 4725);
PAINT MONO (-1811 4725);
FORCEPROP 2 LAST PATH I171
J 0
(-1825 4800);
DISPLAY 1.021277 (-1825 4800);
PAINT ORANGE (-1825 4800);
DISPLAY INVISIBLE (-1825 4800);
FORCEPROP 1 LAST COMMENT_BODY TRUE
J 0
(-2075 4625);
DISPLAY 1.170213 (-2075 4625);
PAINT GREEN (-2075 4625);
DISPLAY INVISIBLE (-2075 4625);
FORCEPROP 1 LAST OFFPAGE TRUE
J 0
(-1700 4600);
DISPLAY 1.170213 (-1700 4600);
PAINT GREEN (-1700 4600);
DISPLAY INVISIBLE (-1700 4600);
FORCEPROP 2 LAST CDS_LIB mstr_standard
J 0
(-2025 4725);
PAINT MONO (-2025 4725);
DISPLAY INVISIBLE (-2025 4725);
FORCEADD SKX_EXT_B..8
(-4200 2550);
FORCEPROP 2 LASTPIN (-5050 1500) $PN CR74
J 2
(-5060 1510);
DISPLAY 0.617021 (-5060 1510);
PAINT ORANGE (-5060 1510);
FORCEPROP 2 LASTPIN (-5050 1550) $PN CN76
J 2
(-5060 1560);
DISPLAY 0.617021 (-5060 1560);
PAINT ORANGE (-5060 1560);
FORCEPROP 2 LASTPIN (-5050 1650) $PN CV77
J 2
(-5060 1660);
DISPLAY 0.617021 (-5060 1660);
PAINT ORANGE (-5060 1660);
FORCEPROP 2 LASTPIN (-5050 1700) $PN CN74
J 2
(-5060 1710);
DISPLAY 0.617021 (-5060 1710);
PAINT ORANGE (-5060 1710);
FORCEPROP 2 LASTPIN (-3350 3000) $PN CV65
J 0
(-3340 3010);
DISPLAY 0.617021 (-3340 3010);
PAINT ORANGE (-3340 3010);
FORCEPROP 2 LASTPIN (-3350 2900) $PN DD77
J 0
(-3340 2910);
DISPLAY 0.617021 (-3340 2910);
PAINT ORANGE (-3340 2910);
FORCEPROP 2 LASTPIN (-3350 3550) $PN DG32
J 0
(-3340 3560);
DISPLAY 0.617021 (-3340 3560);
PAINT ORANGE (-3340 3560);
FORCEPROP 2 LASTPIN (-3350 3850) $PN DE76
J 0
(-3340 3860);
DISPLAY 0.617021 (-3340 3860);
PAINT ORANGE (-3340 3860);
FORCEPROP 2 LASTPIN (-3350 4500) $PN DE32
J 0
(-3340 4510);
DISPLAY 0.617021 (-3340 4510);
PAINT ORANGE (-3340 4510);
FORCEPROP 2 LASTPIN (-5050 2950) $PN CT67
J 2
(-5060 2960);
DISPLAY 0.617021 (-5060 2960);
PAINT ORANGE (-5060 2960);
FORCEPROP 2 LASTPIN (-3350 600) $PN DC62
J 0
(-3340 610);
DISPLAY 0.617021 (-3340 610);
PAINT ORANGE (-3340 610);
FORCEPROP 2 LASTPIN (-3350 550) $PN DD61
J 0
(-3340 560);
DISPLAY 0.617021 (-3340 560);
PAINT ORANGE (-3340 560);
FORCEPROP 2 LASTPIN (-3350 700) $PN DJ52
J 0
(-3340 710);
DISPLAY 0.617021 (-3340 710);
PAINT ORANGE (-3340 710);
FORCEPROP 2 LASTPIN (-3350 750) $PN DC56
J 0
(-3340 760);
DISPLAY 0.617021 (-3340 760);
PAINT ORANGE (-3340 760);
FORCEPROP 2 LASTPIN (-3350 800) $PN DA62
J 0
(-3340 810);
DISPLAY 0.617021 (-3340 810);
PAINT ORANGE (-3340 810);
FORCEPROP 2 LASTPIN (-3350 850) $PN DF61
J 0
(-3340 860);
DISPLAY 0.617021 (-3340 860);
PAINT ORANGE (-3340 860);
FORCEPROP 2 LASTPIN (-5050 500) $PN DF45
J 2
(-5060 510);
DISPLAY 0.617021 (-5060 510);
PAINT ORANGE (-5060 510);
FORCEPROP 2 LASTPIN (-3350 1650) $PN DG62
J 0
(-3340 1660);
DISPLAY 0.617021 (-3340 1660);
PAINT ORANGE (-3340 1660);
FORCEPROP 2 LASTPIN (-3350 1700) $PN DD63
J 0
(-3340 1710);
DISPLAY 0.617021 (-3340 1710);
PAINT ORANGE (-3340 1710);
FORCEPROP 2 LASTPIN (-3350 1750) $PN DK63
J 0
(-3340 1760);
DISPLAY 0.617021 (-3340 1760);
PAINT ORANGE (-3340 1760);
FORCEPROP 2 LASTPIN (-3350 1800) $PN DF63
J 0
(-3340 1810);
DISPLAY 0.617021 (-3340 1810);
PAINT ORANGE (-3340 1810);
FORCEPROP 2 LASTPIN (-5050 600) $PN DK55
J 2
(-5060 610);
DISPLAY 0.617021 (-5060 610);
PAINT ORANGE (-5060 610);
FORCEPROP 2 LASTPIN (-5050 650) $PN DF55
J 2
(-5060 660);
DISPLAY 0.617021 (-5060 660);
PAINT ORANGE (-5060 660);
FORCEPROP 2 LASTPIN (-5050 700) $PN DK57
J 2
(-5060 710);
DISPLAY 0.617021 (-5060 710);
PAINT ORANGE (-5060 710);
FORCEPROP 2 LASTPIN (-5050 750) $PN DF57
J 2
(-5060 760);
DISPLAY 0.617021 (-5060 760);
PAINT ORANGE (-5060 760);
FORCEPROP 2 LASTPIN (-5050 800) $PN DJ54
J 2
(-5060 810);
DISPLAY 0.617021 (-5060 810);
PAINT ORANGE (-5060 810);
FORCEPROP 2 LASTPIN (-5050 850) $PN DG54
J 2
(-5060 860);
DISPLAY 0.617021 (-5060 860);
PAINT ORANGE (-5060 860);
FORCEPROP 2 LASTPIN (-5050 900) $PN DJ56
J 2
(-5060 910);
DISPLAY 0.617021 (-5060 910);
PAINT ORANGE (-5060 910);
FORCEPROP 2 LASTPIN (-5050 950) $PN DG56
J 2
(-5060 960);
DISPLAY 0.617021 (-5060 960);
PAINT ORANGE (-5060 960);
FORCEPROP 2 LASTPIN (-3350 950) $PN DK51
J 0
(-3340 960);
DISPLAY 0.617021 (-3340 960);
PAINT ORANGE (-3340 960);
FORCEPROP 2 LASTPIN (-3350 1000) $PN DF49
J 0
(-3340 1010);
DISPLAY 0.617021 (-3340 1010);
PAINT ORANGE (-3340 1010);
FORCEPROP 2 LASTPIN (-3350 1050) $PN DJ46
J 0
(-3340 1060);
DISPLAY 0.617021 (-3340 1060);
PAINT ORANGE (-3340 1060);
FORCEPROP 2 LASTPIN (-3350 1100) $PN DG46
J 0
(-3340 1110);
DISPLAY 0.617021 (-3340 1110);
PAINT ORANGE (-3340 1110);
FORCEPROP 2 LASTPIN (-3350 1150) $PN DF51
J 0
(-3340 1160);
DISPLAY 0.617021 (-3340 1160);
PAINT ORANGE (-3340 1160);
FORCEPROP 2 LASTPIN (-3350 1200) $PN DJ48
J 0
(-3340 1210);
DISPLAY 0.617021 (-3340 1210);
PAINT ORANGE (-3340 1210);
FORCEPROP 2 LASTPIN (-3350 1250) $PN DM45
J 0
(-3340 1260);
DISPLAY 0.617021 (-3340 1260);
PAINT ORANGE (-3340 1260);
FORCEPROP 2 LASTPIN (-3350 1300) $PN DK45
J 0
(-3340 1310);
DISPLAY 0.617021 (-3340 1310);
PAINT ORANGE (-3340 1310);
FORCEPROP 2 LASTPIN (-5050 1600) $PN CW76
J 2
(-5060 1610);
DISPLAY 0.617021 (-5060 1610);
PAINT ORANGE (-5060 1610);
FORCEPROP 2 LASTPIN (-5050 1750) $PN CM75
J 2
(-5060 1760);
DISPLAY 0.617021 (-5060 1760);
PAINT ORANGE (-5060 1760);
FORCEPROP 2 LASTPIN (-5050 1800) $PN CV75
J 2
(-5060 1810);
DISPLAY 0.617021 (-5060 1810);
PAINT ORANGE (-5060 1810);
FORCEPROP 2 LASTPIN (-5050 1850) $PN CT77
J 2
(-5060 1860);
DISPLAY 0.617021 (-5060 1860);
PAINT ORANGE (-5060 1860);
FORCEPROP 2 LASTPIN (-5050 1900) $PN DE74
J 2
(-5060 1910);
DISPLAY 0.617021 (-5060 1910);
PAINT ORANGE (-5060 1910);
FORCEPROP 2 LASTPIN (-5050 1950) $PN DC76
J 2
(-5060 1960);
DISPLAY 0.617021 (-5060 1960);
PAINT ORANGE (-5060 1960);
FORCEPROP 2 LASTPIN (-5050 2000) $PN DH75
J 2
(-5060 2010);
DISPLAY 0.617021 (-5060 2010);
PAINT ORANGE (-5060 2010);
FORCEPROP 2 LASTPIN (-5050 2050) $PN DJ76
J 2
(-5060 2060);
DISPLAY 0.617021 (-5060 2060);
PAINT ORANGE (-5060 2060);
FORCEPROP 2 LASTPIN (-5050 2100) $PN DC74
J 2
(-5060 2110);
DISPLAY 0.617021 (-5060 2110);
PAINT ORANGE (-5060 2110);
FORCEPROP 2 LASTPIN (-5050 2150) $PN DB75
J 2
(-5060 2160);
DISPLAY 0.617021 (-5060 2160);
PAINT ORANGE (-5060 2160);
FORCEPROP 2 LASTPIN (-5050 2200) $PN DF77
J 2
(-5060 2210);
DISPLAY 0.617021 (-5060 2210);
PAINT ORANGE (-5060 2210);
FORCEPROP 2 LASTPIN (-5050 2250) $PN DH77
J 2
(-5060 2260);
DISPLAY 0.617021 (-5060 2260);
PAINT ORANGE (-5060 2260);
FORCEPROP 2 LASTPIN (-5050 2300) $PN DG70
J 2
(-5060 2310);
DISPLAY 0.617021 (-5060 2310);
PAINT ORANGE (-5060 2310);
FORCEPROP 2 LASTPIN (-5050 2350) $PN DJ72
J 2
(-5060 2360);
DISPLAY 0.617021 (-5060 2360);
PAINT ORANGE (-5060 2360);
FORCEPROP 2 LASTPIN (-5050 2400) $PN DM69
J 2
(-5060 2410);
DISPLAY 0.617021 (-5060 2410);
PAINT ORANGE (-5060 2410);
FORCEPROP 2 LASTPIN (-5050 2450) $PN DN70
J 2
(-5060 2460);
DISPLAY 0.617021 (-5060 2460);
PAINT ORANGE (-5060 2460);
FORCEPROP 2 LASTPIN (-5050 2500) $PN DF71
J 2
(-5060 2510);
DISPLAY 0.617021 (-5060 2510);
PAINT ORANGE (-5060 2510);
FORCEPROP 2 LASTPIN (-5050 2550) $PN DG72
J 2
(-5060 2560);
DISPLAY 0.617021 (-5060 2560);
PAINT ORANGE (-5060 2560);
FORCEPROP 2 LASTPIN (-5050 2600) $PN DK69
J 2
(-5060 2610);
DISPLAY 0.617021 (-5060 2610);
PAINT ORANGE (-5060 2610);
FORCEPROP 2 LASTPIN (-5050 2650) $PN DM71
J 2
(-5060 2660);
DISPLAY 0.617021 (-5060 2660);
PAINT ORANGE (-5060 2660);
FORCEPROP 2 LASTPIN (-5050 2700) $PN CN66
J 2
(-5060 2710);
DISPLAY 0.617021 (-5060 2710);
PAINT ORANGE (-5060 2710);
FORCEPROP 2 LASTPIN (-5050 2750) $PN CU66
J 2
(-5060 2760);
DISPLAY 0.617021 (-5060 2760);
PAINT ORANGE (-5060 2760);
FORCEPROP 2 LASTPIN (-5050 2800) $PN CP63
J 2
(-5060 2810);
DISPLAY 0.617021 (-5060 2810);
PAINT ORANGE (-5060 2810);
FORCEPROP 2 LASTPIN (-5050 2850) $PN CT63
J 2
(-5060 2860);
DISPLAY 0.617021 (-5060 2860);
PAINT ORANGE (-5060 2860);
FORCEPROP 2 LASTPIN (-5050 3000) $PN CN64
J 2
(-5060 3010);
DISPLAY 0.617021 (-5060 3010);
PAINT ORANGE (-5060 3010);
FORCEPROP 2 LASTPIN (-5050 3050) $PN CU64
J 2
(-5060 3060);
DISPLAY 0.617021 (-5060 3060);
PAINT ORANGE (-5060 3060);
FORCEPROP 2 LASTPIN (-5050 3100) $PN DD41
J 2
(-5060 3110);
DISPLAY 0.617021 (-5060 3110);
PAINT ORANGE (-5060 3110);
FORCEPROP 2 LASTPIN (-5050 3150) $PN DG42
J 2
(-5060 3160);
DISPLAY 0.617021 (-5060 3160);
PAINT ORANGE (-5060 3160);
FORCEPROP 2 LASTPIN (-5050 3200) $PN DE38
J 2
(-5060 3210);
DISPLAY 0.617021 (-5060 3210);
PAINT ORANGE (-5060 3210);
FORCEPROP 2 LASTPIN (-5050 3250) $PN DG38
J 2
(-5060 3260);
DISPLAY 0.617021 (-5060 3260);
PAINT ORANGE (-5060 3260);
FORCEPROP 2 LASTPIN (-5050 3300) $PN DA42
J 2
(-5060 3310);
DISPLAY 0.617021 (-5060 3310);
PAINT ORANGE (-5060 3310);
FORCEPROP 2 LASTPIN (-5050 3350) $PN DE42
J 2
(-5060 3360);
DISPLAY 0.617021 (-5060 3360);
PAINT ORANGE (-5060 3360);
FORCEPROP 2 LASTPIN (-5050 3400) $PN DD39
J 2
(-5060 3410);
DISPLAY 0.617021 (-5060 3410);
PAINT ORANGE (-5060 3410);
FORCEPROP 2 LASTPIN (-5050 3450) $PN DH39
J 2
(-5060 3460);
DISPLAY 0.617021 (-5060 3460);
PAINT ORANGE (-5060 3460);
FORCEPROP 2 LASTPIN (-5050 3500) $PN DF33
J 2
(-5060 3510);
DISPLAY 0.617021 (-5060 3510);
PAINT ORANGE (-5060 3510);
FORCEPROP 2 LASTPIN (-5050 3550) $PN DK33
J 2
(-5060 3560);
DISPLAY 0.617021 (-5060 3560);
PAINT ORANGE (-5060 3560);
FORCEPROP 2 LASTPIN (-5050 3600) $PN DG30
J 2
(-5060 3610);
DISPLAY 0.617021 (-5060 3610);
PAINT ORANGE (-5060 3610);
FORCEPROP 2 LASTPIN (-5050 3650) $PN DJ30
J 2
(-5060 3660);
DISPLAY 0.617021 (-5060 3660);
PAINT ORANGE (-5060 3660);
FORCEPROP 2 LASTPIN (-5050 3700) $PN DG34
J 2
(-5060 3710);
DISPLAY 0.617021 (-5060 3710);
PAINT ORANGE (-5060 3710);
FORCEPROP 2 LASTPIN (-5050 3750) $PN DJ34
J 2
(-5060 3760);
DISPLAY 0.617021 (-5060 3760);
PAINT ORANGE (-5060 3760);
FORCEPROP 2 LASTPIN (-5050 3800) $PN DF31
J 2
(-5060 3810);
DISPLAY 0.617021 (-5060 3810);
PAINT ORANGE (-5060 3810);
FORCEPROP 2 LASTPIN (-5050 3850) $PN DK31
J 2
(-5060 3860);
DISPLAY 0.617021 (-5060 3860);
PAINT ORANGE (-5060 3860);
FORCEPROP 2 LASTPIN (-5050 3900) $PN CW36
J 2
(-5060 3910);
DISPLAY 0.617021 (-5060 3910);
PAINT ORANGE (-5060 3910);
FORCEPROP 2 LASTPIN (-5050 3950) $PN DC36
J 2
(-5060 3960);
DISPLAY 0.617021 (-5060 3960);
PAINT ORANGE (-5060 3960);
FORCEPROP 2 LASTPIN (-5050 4000) $PN CY33
J 2
(-5060 4010);
DISPLAY 0.617021 (-5060 4010);
PAINT ORANGE (-5060 4010);
FORCEPROP 2 LASTPIN (-5050 4050) $PN DB33
J 2
(-5060 4060);
DISPLAY 0.617021 (-5060 4060);
PAINT ORANGE (-5060 4060);
FORCEPROP 2 LASTPIN (-5050 4100) $PN CY37
J 2
(-5060 4110);
DISPLAY 0.617021 (-5060 4110);
PAINT ORANGE (-5060 4110);
FORCEPROP 2 LASTPIN (-5050 4150) $PN DB37
J 2
(-5060 4160);
DISPLAY 0.617021 (-5060 4160);
PAINT ORANGE (-5060 4160);
FORCEPROP 2 LASTPIN (-5050 4200) $PN CW34
J 2
(-5060 4210);
DISPLAY 0.617021 (-5060 4210);
PAINT ORANGE (-5060 4210);
FORCEPROP 2 LASTPIN (-5050 4250) $PN DC34
J 2
(-5060 4260);
DISPLAY 0.617021 (-5060 4260);
PAINT ORANGE (-5060 4260);
FORCEPROP 2 LASTPIN (-5050 4300) $PN CW30
J 2
(-5060 4310);
DISPLAY 0.617021 (-5060 4310);
PAINT ORANGE (-5060 4310);
FORCEPROP 2 LASTPIN (-5050 4350) $PN DC30
J 2
(-5060 4360);
DISPLAY 0.617021 (-5060 4360);
PAINT ORANGE (-5060 4360);
FORCEPROP 2 LASTPIN (-5050 4400) $PN CY27
J 2
(-5060 4410);
DISPLAY 0.617021 (-5060 4410);
PAINT ORANGE (-5060 4410);
FORCEPROP 2 LASTPIN (-5050 4450) $PN DB27
J 2
(-5060 4460);
DISPLAY 0.617021 (-5060 4460);
PAINT ORANGE (-5060 4460);
FORCEPROP 2 LASTPIN (-5050 4500) $PN CY31
J 2
(-5060 4510);
DISPLAY 0.617021 (-5060 4510);
PAINT ORANGE (-5060 4510);
FORCEPROP 2 LASTPIN (-5050 4550) $PN DB31
J 2
(-5060 4560);
DISPLAY 0.617021 (-5060 4560);
PAINT ORANGE (-5060 4560);
FORCEPROP 2 LASTPIN (-5050 4600) $PN CW28
J 2
(-5060 4610);
DISPLAY 0.617021 (-5060 4610);
PAINT ORANGE (-5060 4610);
FORCEPROP 2 LASTPIN (-5050 4650) $PN DC28
J 2
(-5060 4660);
DISPLAY 0.617021 (-5060 4660);
PAINT ORANGE (-5060 4660);
FORCEPROP 2 LASTPIN (-3350 2850) $PN CP77
J 0
(-3340 2860);
DISPLAY 0.617021 (-3340 2860);
PAINT ORANGE (-3340 2860);
FORCEPROP 2 LASTPIN (-3350 2950) $PN DL72
J 0
(-3340 2960);
DISPLAY 0.617021 (-3340 2960);
PAINT ORANGE (-3340 2960);
FORCEPROP 2 LASTPIN (-3350 3050) $PN DG40
J 0
(-3340 3060);
DISPLAY 0.617021 (-3340 3060);
PAINT ORANGE (-3340 3060);
FORCEPROP 2 LASTPIN (-3350 3100) $PN DL32
J 0
(-3340 3110);
DISPLAY 0.617021 (-3340 3110);
PAINT ORANGE (-3340 3110);
FORCEPROP 2 LASTPIN (-3350 3150) $PN DD35
J 0
(-3340 3160);
DISPLAY 0.617021 (-3340 3160);
PAINT ORANGE (-3340 3160);
FORCEPROP 2 LASTPIN (-3350 3200) $PN DD29
J 0
(-3340 3210);
DISPLAY 0.617021 (-3340 3210);
PAINT ORANGE (-3340 3210);
FORCEPROP 2 LASTPIN (-3350 3250) $PN CN70
J 0
(-3340 3260);
DISPLAY 0.617021 (-3340 3260);
PAINT ORANGE (-3340 3260);
FORCEPROP 2 LASTPIN (-3350 3300) $PN CT75
J 0
(-3340 3310);
DISPLAY 0.617021 (-3340 3310);
PAINT ORANGE (-3340 3310);
FORCEPROP 2 LASTPIN (-3350 3350) $PN DF75
J 0
(-3340 3360);
DISPLAY 0.617021 (-3340 3360);
PAINT ORANGE (-3340 3360);
FORCEPROP 2 LASTPIN (-3350 3400) $PN DJ70
J 0
(-3340 3410);
DISPLAY 0.617021 (-3340 3410);
PAINT ORANGE (-3340 3410);
FORCEPROP 2 LASTPIN (-3350 3450) $PN CP65
J 0
(-3340 3460);
DISPLAY 0.617021 (-3340 3460);
PAINT ORANGE (-3340 3460);
FORCEPROP 2 LASTPIN (-3350 3500) $PN DE40
J 0
(-3340 3510);
DISPLAY 0.617021 (-3340 3510);
PAINT ORANGE (-3340 3510);
FORCEPROP 2 LASTPIN (-3350 3600) $PN CY35
J 0
(-3340 3610);
DISPLAY 0.617021 (-3340 3610);
PAINT ORANGE (-3340 3610);
FORCEPROP 2 LASTPIN (-3350 3650) $PN CY29
J 0
(-3340 3660);
DISPLAY 0.617021 (-3340 3660);
PAINT ORANGE (-3340 3660);
FORCEPROP 2 LASTPIN (-3350 3700) $PN CJ70
J 0
(-3340 3710);
DISPLAY 0.617021 (-3340 3710);
PAINT ORANGE (-3340 3710);
FORCEPROP 2 LASTPIN (-3350 3800) $PN CR76
J 0
(-3340 3810);
DISPLAY 0.617021 (-3340 3810);
PAINT ORANGE (-3340 3810);
FORCEPROP 2 LASTPIN (-3350 3900) $PN DK71
J 0
(-3340 3910);
DISPLAY 0.617021 (-3340 3910);
PAINT ORANGE (-3340 3910);
FORCEPROP 2 LASTPIN (-3350 3950) $PN CT65
J 0
(-3340 3960);
DISPLAY 0.617021 (-3340 3960);
PAINT ORANGE (-3340 3960);
FORCEPROP 2 LASTPIN (-3350 4000) $PN DJ40
J 0
(-3340 4010);
DISPLAY 0.617021 (-3340 4010);
PAINT ORANGE (-3340 4010);
FORCEPROP 2 LASTPIN (-3350 4050) $PN DJ32
J 0
(-3340 4060);
DISPLAY 0.617021 (-3340 4060);
PAINT ORANGE (-3340 4060);
FORCEPROP 2 LASTPIN (-3350 4100) $PN DB35
J 0
(-3340 4110);
DISPLAY 0.617021 (-3340 4110);
PAINT ORANGE (-3340 4110);
FORCEPROP 2 LASTPIN (-3350 4200) $PN CL70
J 0
(-3340 4210);
DISPLAY 0.617021 (-3340 4210);
PAINT ORANGE (-3340 4210);
FORCEPROP 2 LASTPIN (-3350 4250) $PN CU74
J 0
(-3340 4260);
DISPLAY 0.617021 (-3340 4260);
PAINT ORANGE (-3340 4260);
FORCEPROP 2 LASTPIN (-3350 4300) $PN DG74
J 0
(-3340 4310);
DISPLAY 0.617021 (-3340 4310);
PAINT ORANGE (-3340 4310);
FORCEPROP 2 LASTPIN (-3350 4350) $PN DH69
J 0
(-3340 4360);
DISPLAY 0.617021 (-3340 4360);
PAINT ORANGE (-3340 4360);
FORCEPROP 2 LASTPIN (-3350 4400) $PN CM65
J 0
(-3340 4410);
DISPLAY 0.617021 (-3340 4410);
PAINT ORANGE (-3340 4410);
FORCEPROP 2 LASTPIN (-3350 4450) $PN DC40
J 0
(-3340 4460);
DISPLAY 0.617021 (-3340 4460);
PAINT ORANGE (-3340 4460);
FORCEPROP 2 LASTPIN (-3350 4550) $PN CV35
J 0
(-3340 4560);
DISPLAY 0.617021 (-3340 4560);
PAINT ORANGE (-3340 4560);
FORCEPROP 2 LASTPIN (-3350 4600) $PN CV29
J 0
(-3340 4610);
DISPLAY 0.617021 (-3340 4610);
PAINT ORANGE (-3340 4610);
FORCEPROP 2 LASTPIN (-3350 4650) $PN CG70
J 0
(-3340 4660);
DISPLAY 0.617021 (-3340 4660);
PAINT ORANGE (-3340 4660);
FORCEPROP 2 LASTPIN (-5050 1050) $PN CH71
J 2
(-5060 1060);
DISPLAY 0.617021 (-5060 1060);
PAINT ORANGE (-5060 1060);
FORCEPROP 2 LASTPIN (-5050 1100) $PN CM71
J 2
(-5060 1110);
DISPLAY 0.617021 (-5060 1110);
PAINT ORANGE (-5060 1110);
FORCEPROP 2 LASTPIN (-5050 1150) $PN CJ68
J 2
(-5060 1160);
DISPLAY 0.617021 (-5060 1160);
PAINT ORANGE (-5060 1160);
FORCEPROP 2 LASTPIN (-5050 1200) $PN CL68
J 2
(-5060 1210);
DISPLAY 0.617021 (-5060 1210);
PAINT ORANGE (-5060 1210);
FORCEPROP 2 LASTPIN (-5050 1250) $PN CJ72
J 2
(-5060 1260);
DISPLAY 0.617021 (-5060 1260);
PAINT ORANGE (-5060 1260);
FORCEPROP 2 LASTPIN (-5050 1300) $PN CL72
J 2
(-5060 1310);
DISPLAY 0.617021 (-5060 1310);
PAINT ORANGE (-5060 1310);
FORCEPROP 2 LASTPIN (-5050 1350) $PN CH69
J 2
(-5060 1360);
DISPLAY 0.617021 (-5060 1360);
PAINT ORANGE (-5060 1360);
FORCEPROP 2 LASTPIN (-5050 1400) $PN CM69
J 2
(-5060 1410);
DISPLAY 0.617021 (-5060 1410);
PAINT ORANGE (-5060 1410);
FORCEPROP 2 LASTPIN (-3350 1900) $PN DF53
J 0
(-3340 1910);
DISPLAY 0.617021 (-3340 1910);
PAINT ORANGE (-3340 1910);
FORCEPROP 2 LASTPIN (-3350 1950) $PN DC58
J 0
(-3340 1960);
DISPLAY 0.617021 (-3340 1960);
PAINT ORANGE (-3340 1960);
FORCEPROP 2 LASTPIN (-3350 2000) $PN DD57
J 0
(-3340 2010);
DISPLAY 0.617021 (-3340 2010);
PAINT ORANGE (-3340 2010);
FORCEPROP 2 LASTPIN (-3350 2050) $PN DG58
J 0
(-3340 2060);
DISPLAY 0.617021 (-3340 2060);
PAINT ORANGE (-3340 2060);
FORCEPROP 2 LASTPIN (-3350 2100) $PN DJ58
J 0
(-3340 2110);
DISPLAY 0.617021 (-3340 2110);
PAINT ORANGE (-3340 2110);
FORCEPROP 2 LASTPIN (-3350 2150) $PN DF59
J 0
(-3340 2160);
DISPLAY 0.617021 (-3340 2160);
PAINT ORANGE (-3340 2160);
FORCEPROP 2 LASTPIN (-3350 2200) $PN DK59
J 0
(-3340 2210);
DISPLAY 0.617021 (-3340 2210);
PAINT ORANGE (-3340 2210);
FORCEPROP 2 LASTPIN (-3350 2250) $PN DC60
J 0
(-3340 2260);
DISPLAY 0.617021 (-3340 2260);
PAINT ORANGE (-3340 2260);
FORCEPROP 2 LASTPIN (-3350 2300) $PN DD59
J 0
(-3340 2310);
DISPLAY 0.617021 (-3340 2310);
PAINT ORANGE (-3340 2310);
FORCEPROP 2 LASTPIN (-3350 2350) $PN DA58
J 0
(-3340 2360);
DISPLAY 0.617021 (-3340 2360);
PAINT ORANGE (-3340 2360);
FORCEPROP 2 LASTPIN (-3350 2400) $PN DD55
J 0
(-3340 2410);
DISPLAY 0.617021 (-3340 2410);
PAINT ORANGE (-3340 2410);
FORCEPROP 2 LASTPIN (-3350 2450) $PN DA60
J 0
(-3340 2460);
DISPLAY 0.617021 (-3340 2460);
PAINT ORANGE (-3340 2460);
FORCEPROP 2 LASTPIN (-3350 2500) $PN DG60
J 0
(-3340 2510);
DISPLAY 0.617021 (-3340 2510);
PAINT ORANGE (-3340 2510);
FORCEPROP 2 LASTPIN (-3350 2550) $PN DD53
J 0
(-3340 2560);
DISPLAY 0.617021 (-3340 2560);
PAINT ORANGE (-3340 2560);
FORCEPROP 2 LASTPIN (-3350 2600) $PN DJ50
J 0
(-3340 2610);
DISPLAY 0.617021 (-3340 2610);
PAINT ORANGE (-3340 2610);
FORCEPROP 2 LASTPIN (-3350 2650) $PN DC54
J 0
(-3340 2660);
DISPLAY 0.617021 (-3340 2660);
PAINT ORANGE (-3340 2660);
FORCEPROP 2 LASTPIN (-3350 2700) $PN DG52
J 0
(-3340 2710);
DISPLAY 0.617021 (-3340 2710);
PAINT ORANGE (-3340 2710);
FORCEPROP 2 LASTPIN (-3350 2750) $PN DE46
J 0
(-3340 2760);
DISPLAY 0.617021 (-3340 2760);
PAINT ORANGE (-3340 2760);
FORCEPROP 2 LASTPIN (-3350 1400) $PN DG50
J 0
(-3340 1410);
DISPLAY 0.617021 (-3340 1410);
PAINT ORANGE (-3340 1410);
FORCEPROP 2 LASTPIN (-3350 1450) $PN DG48
J 0
(-3340 1460);
DISPLAY 0.617021 (-3340 1460);
PAINT ORANGE (-3340 1460);
FORCEPROP 2 LASTPIN (-3350 1500) $PN DK49
J 0
(-3340 1510);
DISPLAY 0.617021 (-3340 1510);
PAINT ORANGE (-3340 1510);
FORCEPROP 2 LASTPIN (-3350 1550) $PN DF47
J 0
(-3340 1560);
DISPLAY 0.617021 (-3340 1560);
PAINT ORANGE (-3340 1560);
FORCEPROP 2 LASTPIN (-3350 500) $PN DK53
J 0
(-3340 510);
DISPLAY 0.617021 (-3340 510);
PAINT ORANGE (-3340 510);
FORCEPROP 1 LAST MATERIAL IC
J 0
(-5000 4850);
DISPLAY 0.617021 (-5000 4850);
PAINT SKYBLUE (-5000 4850);
FORCEPROP 1 LAST PART_NUMBER TBD
J 0
(-5000 300);
DISPLAY 0.617021 (-5000 300);
PAINT BLUE (-5000 300);
FORCEPROP 1 LAST LOCATION U2D1
J 0
(-5000 4900);
DISPLAY 0.617021 (-5000 4900);
PAINT AQUA (-5000 4900);
FORCEPROP 2 LASTPIN (-3350 4150) $PN DB29
J 0
(-3340 4160);
DISPLAY 0.617021 (-3340 4160);
PAINT ORANGE (-3340 4160);
FORCEPROP 2 LASTPIN (-5050 2900) $PN CP67
J 2
(-5060 2910);
DISPLAY 0.617021 (-5060 2910);
PAINT ORANGE (-5060 2910);
FORCEPROP 1 LAST PATH I172
J 0
(-4200 4850);
PAINT GREEN (-4200 4850);
DISPLAY INVISIBLE (-4200 4850);
FORCEPROP 2 LAST CDS_LOCATION U2D1
J 0
(-5000 4900);
DISPLAY 0.617021 (-5000 4900);
PAINT AQUA (-5000 4900);
DISPLAY INVISIBLE (-5000 4900);
FORCEPROP 2 LAST SEC 8
J 0
(-5000 4950);
DISPLAY 0.680851 (-5000 4950);
PAINT MONO (-5000 4950);
DISPLAY INVISIBLE (-5000 4950);
FORCEPROP 2 LAST CDS_LIB chpset_lib
J 0
(-4200 2550);
PAINT ORANGE (-4200 2550);
DISPLAY INVISIBLE (-4200 2550);
FORCEPROP 2 LAST SEC_TYPE BGA1
J 0
(-5000 4950);
DISPLAY 1.021277 (-5000 4950);
PAINT ORANGE (-5000 4950);
DISPLAY INVISIBLE (-5000 4950);
FORCEPROP 1 LAST PACK_TYPE BGA1
J 0
(-5000 4950);
PAINT SKYBLUE (-5000 4950);
DISPLAY INVISIBLE (-5000 4950);
FORCEADD TAP..6
(-5600 1300);
FORCEPROP 3 LASTPIN (-5550 1300) SIG_NAME M_M_ECC<5>
J 0
(-5540 1310);
DISPLAY 0.659574 (-5540 1310);
PAINT MONO (-5540 1310);
DISPLAY INVISIBLE (-5540 1310);
FORCEPROP 1 LASTPIN (-5550 1300) BN 5
J 0
(-5602 1308);
DISPLAY 0.617021 (-5602 1308);
PAINT GREEN (-5602 1308);
FORCEPROP 1 LAST PATH I18
J 0
(-5602 1300);
DISPLAY 0.872340 (-5602 1300);
PAINT GREEN (-5602 1300);
DISPLAY INVISIBLE (-5602 1300);
FORCEPROP 1 LAST HDL_TAP TRUE
J 0
(-5275 1175);
DISPLAY 1.595745 (-5275 1175);
PAINT GREEN (-5275 1175);
DISPLAY INVISIBLE (-5275 1175);
FORCEPROP 1 LAST BODY_TYPE PLUMBING
J 0
(-5600 1250);
DISPLAY 1.595745 (-5600 1250);
PAINT GREEN (-5600 1250);
DISPLAY INVISIBLE (-5600 1250);
FORCEPROP 2 LAST CDS_LIB mstr_standard
J 0
(-5600 1300);
PAINT MONO (-5600 1300);
DISPLAY INVISIBLE (-5600 1300);
FORCEADD TAP..6
(-5600 1350);
FORCEPROP 3 LASTPIN (-5550 1350) SIG_NAME M_M_ECC<6>
J 0
(-5540 1360);
DISPLAY 0.659574 (-5540 1360);
PAINT MONO (-5540 1360);
DISPLAY INVISIBLE (-5540 1360);
FORCEPROP 1 LASTPIN (-5550 1350) BN 6
J 0
(-5602 1358);
DISPLAY 0.617021 (-5602 1358);
PAINT GREEN (-5602 1358);
FORCEPROP 1 LAST PATH I19
J 0
(-5602 1350);
DISPLAY 0.872340 (-5602 1350);
PAINT GREEN (-5602 1350);
DISPLAY INVISIBLE (-5602 1350);
FORCEPROP 1 LAST HDL_TAP TRUE
J 0
(-5275 1225);
DISPLAY 1.595745 (-5275 1225);
PAINT GREEN (-5275 1225);
DISPLAY INVISIBLE (-5275 1225);
FORCEPROP 1 LAST BODY_TYPE PLUMBING
J 0
(-5600 1300);
DISPLAY 1.595745 (-5600 1300);
PAINT GREEN (-5600 1300);
DISPLAY INVISIBLE (-5600 1300);
FORCEPROP 2 LAST CDS_LIB mstr_standard
J 0
(-5600 1350);
PAINT MONO (-5600 1350);
DISPLAY INVISIBLE (-5600 1350);
FORCEADD OFFPAGE..5
(-6450 800);
FORCEPROP 2 LAST $XR1 88 
J 0
(-6764 800);
DISPLAY 0.638298 (-6764 800);
PAINT MONO (-6764 800);
FORCEPROP 2 LAST $XR0 87 
J 0
(-6674 800);
DISPLAY 0.638298 (-6674 800);
PAINT MONO (-6674 800);
FORCEPROP 2 LAST PATH I2
J 0
(-6400 875);
DISPLAY 1.021277 (-6400 875);
PAINT ORANGE (-6400 875);
DISPLAY INVISIBLE (-6400 875);
FORCEPROP 1 LAST COMMENT_BODY TRUE
J 0
(-6350 725);
DISPLAY 1.170213 (-6350 725);
PAINT GREEN (-6350 725);
DISPLAY INVISIBLE (-6350 725);
FORCEPROP 1 LAST OFFPAGE TRUE
J 0
(-6125 675);
DISPLAY 1.170213 (-6125 675);
PAINT GREEN (-6125 675);
DISPLAY INVISIBLE (-6125 675);
FORCEPROP 2 LAST CDS_LIB mstr_standard
J 0
(-6450 800);
PAINT MONO (-6450 800);
DISPLAY INVISIBLE (-6450 800);
FORCEADD TAP..6
(-5600 1400);
FORCEPROP 3 LASTPIN (-5550 1400) SIG_NAME M_M_ECC<7>
J 0
(-5540 1410);
DISPLAY 0.659574 (-5540 1410);
PAINT MONO (-5540 1410);
DISPLAY INVISIBLE (-5540 1410);
FORCEPROP 1 LASTPIN (-5550 1400) BN 7
J 0
(-5602 1408);
DISPLAY 0.617021 (-5602 1408);
PAINT GREEN (-5602 1408);
FORCEPROP 1 LAST PATH I20
J 0
(-5602 1400);
DISPLAY 0.872340 (-5602 1400);
PAINT GREEN (-5602 1400);
DISPLAY INVISIBLE (-5602 1400);
FORCEPROP 1 LAST HDL_TAP TRUE
J 0
(-5275 1275);
DISPLAY 1.595745 (-5275 1275);
PAINT GREEN (-5275 1275);
DISPLAY INVISIBLE (-5275 1275);
FORCEPROP 1 LAST BODY_TYPE PLUMBING
J 0
(-5600 1350);
DISPLAY 1.595745 (-5600 1350);
PAINT GREEN (-5600 1350);
DISPLAY INVISIBLE (-5600 1350);
FORCEPROP 2 LAST CDS_LIB mstr_standard
J 0
(-5600 1400);
PAINT MONO (-5600 1400);
DISPLAY INVISIBLE (-5600 1400);
FORCEADD TAP..6
(-5600 1500);
FORCEPROP 3 LASTPIN (-5550 1500) SIG_NAME M_M_DQ<0>
J 0
(-5540 1510);
DISPLAY 0.659574 (-5540 1510);
PAINT MONO (-5540 1510);
DISPLAY INVISIBLE (-5540 1510);
FORCEPROP 1 LASTPIN (-5550 1500) BN 0
J 0
(-5602 1508);
DISPLAY 0.617021 (-5602 1508);
PAINT GREEN (-5602 1508);
FORCEPROP 1 LAST PATH I21
J 0
(-5602 1500);
DISPLAY 0.872340 (-5602 1500);
PAINT GREEN (-5602 1500);
DISPLAY INVISIBLE (-5602 1500);
FORCEPROP 1 LAST HDL_TAP TRUE
J 0
(-5275 1375);
DISPLAY 1.595745 (-5275 1375);
PAINT GREEN (-5275 1375);
DISPLAY INVISIBLE (-5275 1375);
FORCEPROP 1 LAST BODY_TYPE PLUMBING
J 0
(-5600 1450);
DISPLAY 1.595745 (-5600 1450);
PAINT GREEN (-5600 1450);
DISPLAY INVISIBLE (-5600 1450);
FORCEPROP 2 LAST CDS_LIB mstr_standard
J 0
(-5600 1500);
PAINT MONO (-5600 1500);
DISPLAY INVISIBLE (-5600 1500);
FORCEADD TAP..6
(-5600 1550);
FORCEPROP 3 LASTPIN (-5550 1550) SIG_NAME M_M_DQ<1>
J 0
(-5540 1560);
DISPLAY 0.659574 (-5540 1560);
PAINT MONO (-5540 1560);
DISPLAY INVISIBLE (-5540 1560);
FORCEPROP 1 LASTPIN (-5550 1550) BN 1
J 0
(-5602 1558);
DISPLAY 0.617021 (-5602 1558);
PAINT GREEN (-5602 1558);
FORCEPROP 1 LAST PATH I22
J 0
(-5602 1550);
DISPLAY 0.872340 (-5602 1550);
PAINT GREEN (-5602 1550);
DISPLAY INVISIBLE (-5602 1550);
FORCEPROP 1 LAST HDL_TAP TRUE
J 0
(-5275 1425);
DISPLAY 1.595745 (-5275 1425);
PAINT GREEN (-5275 1425);
DISPLAY INVISIBLE (-5275 1425);
FORCEPROP 1 LAST BODY_TYPE PLUMBING
J 0
(-5600 1500);
DISPLAY 1.595745 (-5600 1500);
PAINT GREEN (-5600 1500);
DISPLAY INVISIBLE (-5600 1500);
FORCEPROP 2 LAST CDS_LIB mstr_standard
J 0
(-5600 1550);
PAINT MONO (-5600 1550);
DISPLAY INVISIBLE (-5600 1550);
FORCEADD TAP..6
(-5600 1600);
FORCEPROP 3 LASTPIN (-5550 1600) SIG_NAME M_M_DQ<2>
J 0
(-5540 1610);
DISPLAY 0.659574 (-5540 1610);
PAINT MONO (-5540 1610);
DISPLAY INVISIBLE (-5540 1610);
FORCEPROP 1 LASTPIN (-5550 1600) BN 2
J 0
(-5602 1608);
DISPLAY 0.617021 (-5602 1608);
PAINT GREEN (-5602 1608);
FORCEPROP 1 LAST PATH I23
J 0
(-5602 1600);
DISPLAY 0.872340 (-5602 1600);
PAINT GREEN (-5602 1600);
DISPLAY INVISIBLE (-5602 1600);
FORCEPROP 1 LAST HDL_TAP TRUE
J 0
(-5275 1475);
DISPLAY 1.595745 (-5275 1475);
PAINT GREEN (-5275 1475);
DISPLAY INVISIBLE (-5275 1475);
FORCEPROP 1 LAST BODY_TYPE PLUMBING
J 0
(-5600 1550);
DISPLAY 1.595745 (-5600 1550);
PAINT GREEN (-5600 1550);
DISPLAY INVISIBLE (-5600 1550);
FORCEPROP 2 LAST CDS_LIB mstr_standard
J 0
(-5600 1600);
PAINT MONO (-5600 1600);
DISPLAY INVISIBLE (-5600 1600);
FORCEADD TAP..6
(-5600 1650);
FORCEPROP 3 LASTPIN (-5550 1650) SIG_NAME M_M_DQ<3>
J 0
(-5540 1660);
DISPLAY 0.659574 (-5540 1660);
PAINT MONO (-5540 1660);
DISPLAY INVISIBLE (-5540 1660);
FORCEPROP 1 LASTPIN (-5550 1650) BN 3
J 0
(-5602 1658);
DISPLAY 0.617021 (-5602 1658);
PAINT GREEN (-5602 1658);
FORCEPROP 1 LAST PATH I24
J 0
(-5602 1650);
DISPLAY 0.872340 (-5602 1650);
PAINT GREEN (-5602 1650);
DISPLAY INVISIBLE (-5602 1650);
FORCEPROP 1 LAST HDL_TAP TRUE
J 0
(-5275 1525);
DISPLAY 1.595745 (-5275 1525);
PAINT GREEN (-5275 1525);
DISPLAY INVISIBLE (-5275 1525);
FORCEPROP 1 LAST BODY_TYPE PLUMBING
J 0
(-5600 1600);
DISPLAY 1.595745 (-5600 1600);
PAINT GREEN (-5600 1600);
DISPLAY INVISIBLE (-5600 1600);
FORCEPROP 2 LAST CDS_LIB mstr_standard
J 0
(-5600 1650);
PAINT MONO (-5600 1650);
DISPLAY INVISIBLE (-5600 1650);
FORCEADD TAP..6
(-5600 1700);
FORCEPROP 3 LASTPIN (-5550 1700) SIG_NAME M_M_DQ<4>
J 0
(-5540 1710);
DISPLAY 0.659574 (-5540 1710);
PAINT MONO (-5540 1710);
DISPLAY INVISIBLE (-5540 1710);
FORCEPROP 1 LASTPIN (-5550 1700) BN 4
J 0
(-5602 1708);
DISPLAY 0.617021 (-5602 1708);
PAINT GREEN (-5602 1708);
FORCEPROP 1 LAST PATH I25
J 0
(-5602 1700);
DISPLAY 0.872340 (-5602 1700);
PAINT GREEN (-5602 1700);
DISPLAY INVISIBLE (-5602 1700);
FORCEPROP 1 LAST HDL_TAP TRUE
J 0
(-5275 1575);
DISPLAY 1.595745 (-5275 1575);
PAINT GREEN (-5275 1575);
DISPLAY INVISIBLE (-5275 1575);
FORCEPROP 1 LAST BODY_TYPE PLUMBING
J 0
(-5600 1650);
DISPLAY 1.595745 (-5600 1650);
PAINT GREEN (-5600 1650);
DISPLAY INVISIBLE (-5600 1650);
FORCEPROP 2 LAST CDS_LIB mstr_standard
J 0
(-5600 1700);
PAINT MONO (-5600 1700);
DISPLAY INVISIBLE (-5600 1700);
FORCEADD TAP..6
(-5600 1750);
FORCEPROP 3 LASTPIN (-5550 1750) SIG_NAME M_M_DQ<5>
J 0
(-5540 1760);
DISPLAY 0.659574 (-5540 1760);
PAINT MONO (-5540 1760);
DISPLAY INVISIBLE (-5540 1760);
FORCEPROP 1 LASTPIN (-5550 1750) BN 5
J 0
(-5602 1758);
DISPLAY 0.617021 (-5602 1758);
PAINT GREEN (-5602 1758);
FORCEPROP 1 LAST PATH I26
J 0
(-5602 1750);
DISPLAY 0.872340 (-5602 1750);
PAINT GREEN (-5602 1750);
DISPLAY INVISIBLE (-5602 1750);
FORCEPROP 1 LAST HDL_TAP TRUE
J 0
(-5275 1625);
DISPLAY 1.595745 (-5275 1625);
PAINT GREEN (-5275 1625);
DISPLAY INVISIBLE (-5275 1625);
FORCEPROP 1 LAST BODY_TYPE PLUMBING
J 0
(-5600 1700);
DISPLAY 1.595745 (-5600 1700);
PAINT GREEN (-5600 1700);
DISPLAY INVISIBLE (-5600 1700);
FORCEPROP 2 LAST CDS_LIB mstr_standard
J 0
(-5600 1750);
PAINT MONO (-5600 1750);
DISPLAY INVISIBLE (-5600 1750);
FORCEADD TAP..6
(-5600 1800);
FORCEPROP 3 LASTPIN (-5550 1800) SIG_NAME M_M_DQ<6>
J 0
(-5540 1810);
DISPLAY 0.659574 (-5540 1810);
PAINT MONO (-5540 1810);
DISPLAY INVISIBLE (-5540 1810);
FORCEPROP 1 LASTPIN (-5550 1800) BN 6
J 0
(-5602 1808);
DISPLAY 0.617021 (-5602 1808);
PAINT GREEN (-5602 1808);
FORCEPROP 1 LAST PATH I27
J 0
(-5602 1800);
DISPLAY 0.872340 (-5602 1800);
PAINT GREEN (-5602 1800);
DISPLAY INVISIBLE (-5602 1800);
FORCEPROP 1 LAST HDL_TAP TRUE
J 0
(-5275 1675);
DISPLAY 1.595745 (-5275 1675);
PAINT GREEN (-5275 1675);
DISPLAY INVISIBLE (-5275 1675);
FORCEPROP 1 LAST BODY_TYPE PLUMBING
J 0
(-5600 1750);
DISPLAY 1.595745 (-5600 1750);
PAINT GREEN (-5600 1750);
DISPLAY INVISIBLE (-5600 1750);
FORCEPROP 2 LAST CDS_LIB mstr_standard
J 0
(-5600 1800);
PAINT MONO (-5600 1800);
DISPLAY INVISIBLE (-5600 1800);
FORCEADD TAP..6
(-5600 1900);
FORCEPROP 3 LASTPIN (-5550 1900) SIG_NAME M_M_DQ<8>
J 0
(-5540 1910);
DISPLAY 0.659574 (-5540 1910);
PAINT MONO (-5540 1910);
DISPLAY INVISIBLE (-5540 1910);
FORCEPROP 1 LASTPIN (-5550 1900) BN 8
J 0
(-5602 1908);
DISPLAY 0.617021 (-5602 1908);
PAINT GREEN (-5602 1908);
FORCEPROP 1 LAST PATH I28
J 0
(-5602 1900);
DISPLAY 0.872340 (-5602 1900);
PAINT GREEN (-5602 1900);
DISPLAY INVISIBLE (-5602 1900);
FORCEPROP 1 LAST HDL_TAP TRUE
J 0
(-5275 1775);
DISPLAY 1.595745 (-5275 1775);
PAINT GREEN (-5275 1775);
DISPLAY INVISIBLE (-5275 1775);
FORCEPROP 1 LAST BODY_TYPE PLUMBING
J 0
(-5600 1850);
DISPLAY 1.595745 (-5600 1850);
PAINT GREEN (-5600 1850);
DISPLAY INVISIBLE (-5600 1850);
FORCEPROP 2 LAST CDS_LIB mstr_standard
J 0
(-5600 1900);
PAINT MONO (-5600 1900);
DISPLAY INVISIBLE (-5600 1900);
FORCEADD TAP..6
(-5600 1850);
FORCEPROP 3 LASTPIN (-5550 1850) SIG_NAME M_M_DQ<7>
J 0
(-5540 1860);
DISPLAY 0.659574 (-5540 1860);
PAINT MONO (-5540 1860);
DISPLAY INVISIBLE (-5540 1860);
FORCEPROP 1 LASTPIN (-5550 1850) BN 7
J 0
(-5602 1858);
DISPLAY 0.617021 (-5602 1858);
PAINT GREEN (-5602 1858);
FORCEPROP 1 LAST PATH I29
J 0
(-5602 1850);
DISPLAY 0.872340 (-5602 1850);
PAINT GREEN (-5602 1850);
DISPLAY INVISIBLE (-5602 1850);
FORCEPROP 1 LAST HDL_TAP TRUE
J 0
(-5275 1725);
DISPLAY 1.595745 (-5275 1725);
PAINT GREEN (-5275 1725);
DISPLAY INVISIBLE (-5275 1725);
FORCEPROP 1 LAST BODY_TYPE PLUMBING
J 0
(-5600 1800);
DISPLAY 1.595745 (-5600 1800);
PAINT GREEN (-5600 1800);
DISPLAY INVISIBLE (-5600 1800);
FORCEPROP 2 LAST CDS_LIB mstr_standard
J 0
(-5600 1850);
PAINT MONO (-5600 1850);
DISPLAY INVISIBLE (-5600 1850);
FORCEADD OFFPAGE..5
(-6450 1000);
FORCEPROP 2 LAST $XR1 88 
J 0
(-6764 1000);
DISPLAY 0.638298 (-6764 1000);
PAINT MONO (-6764 1000);
FORCEPROP 2 LAST $XR0 87 
J 0
(-6674 1000);
DISPLAY 0.638298 (-6674 1000);
PAINT MONO (-6674 1000);
FORCEPROP 2 LAST PATH I3
J 0
(-6400 1075);
DISPLAY 1.021277 (-6400 1075);
PAINT ORANGE (-6400 1075);
DISPLAY INVISIBLE (-6400 1075);
FORCEPROP 1 LAST COMMENT_BODY TRUE
J 0
(-6350 925);
DISPLAY 1.170213 (-6350 925);
PAINT GREEN (-6350 925);
DISPLAY INVISIBLE (-6350 925);
FORCEPROP 1 LAST OFFPAGE TRUE
J 0
(-6125 875);
DISPLAY 1.170213 (-6125 875);
PAINT GREEN (-6125 875);
DISPLAY INVISIBLE (-6125 875);
FORCEPROP 2 LAST CDS_LIB mstr_standard
J 0
(-6450 1000);
PAINT MONO (-6450 1000);
DISPLAY INVISIBLE (-6450 1000);
FORCEADD TAP..6
(-5600 1950);
FORCEPROP 3 LASTPIN (-5550 1950) SIG_NAME M_M_DQ<9>
J 0
(-5540 1960);
DISPLAY 0.659574 (-5540 1960);
PAINT MONO (-5540 1960);
DISPLAY INVISIBLE (-5540 1960);
FORCEPROP 1 LASTPIN (-5550 1950) BN 9
J 0
(-5602 1958);
DISPLAY 0.617021 (-5602 1958);
PAINT GREEN (-5602 1958);
FORCEPROP 1 LAST PATH I31
J 0
(-5602 1950);
DISPLAY 0.872340 (-5602 1950);
PAINT GREEN (-5602 1950);
DISPLAY INVISIBLE (-5602 1950);
FORCEPROP 1 LAST HDL_TAP TRUE
J 0
(-5275 1825);
DISPLAY 1.595745 (-5275 1825);
PAINT GREEN (-5275 1825);
DISPLAY INVISIBLE (-5275 1825);
FORCEPROP 1 LAST BODY_TYPE PLUMBING
J 0
(-5600 1900);
DISPLAY 1.595745 (-5600 1900);
PAINT GREEN (-5600 1900);
DISPLAY INVISIBLE (-5600 1900);
FORCEPROP 2 LAST CDS_LIB mstr_standard
J 0
(-5600 1950);
PAINT MONO (-5600 1950);
DISPLAY INVISIBLE (-5600 1950);
FORCEADD TAP..6
(-5600 2000);
FORCEPROP 3 LASTPIN (-5550 2000) SIG_NAME M_M_DQ<10>
J 0
(-5540 2010);
DISPLAY 0.659574 (-5540 2010);
PAINT MONO (-5540 2010);
DISPLAY INVISIBLE (-5540 2010);
FORCEPROP 1 LASTPIN (-5550 2000) BN 10
J 0
(-5602 2008);
DISPLAY 0.617021 (-5602 2008);
PAINT GREEN (-5602 2008);
FORCEPROP 1 LAST PATH I32
J 0
(-5602 2000);
DISPLAY 0.872340 (-5602 2000);
PAINT GREEN (-5602 2000);
DISPLAY INVISIBLE (-5602 2000);
FORCEPROP 1 LAST HDL_TAP TRUE
J 0
(-5275 1875);
DISPLAY 1.595745 (-5275 1875);
PAINT GREEN (-5275 1875);
DISPLAY INVISIBLE (-5275 1875);
FORCEPROP 1 LAST BODY_TYPE PLUMBING
J 0
(-5600 1950);
DISPLAY 1.595745 (-5600 1950);
PAINT GREEN (-5600 1950);
DISPLAY INVISIBLE (-5600 1950);
FORCEPROP 2 LAST CDS_LIB mstr_standard
J 0
(-5600 2000);
PAINT MONO (-5600 2000);
DISPLAY INVISIBLE (-5600 2000);
FORCEADD TAP..6
(-5600 2050);
FORCEPROP 3 LASTPIN (-5550 2050) SIG_NAME M_M_DQ<11>
J 0
(-5540 2060);
DISPLAY 0.659574 (-5540 2060);
PAINT MONO (-5540 2060);
DISPLAY INVISIBLE (-5540 2060);
FORCEPROP 1 LASTPIN (-5550 2050) BN 11
J 0
(-5602 2058);
DISPLAY 0.617021 (-5602 2058);
PAINT GREEN (-5602 2058);
FORCEPROP 1 LAST PATH I33
J 0
(-5602 2050);
DISPLAY 0.872340 (-5602 2050);
PAINT GREEN (-5602 2050);
DISPLAY INVISIBLE (-5602 2050);
FORCEPROP 1 LAST HDL_TAP TRUE
J 0
(-5275 1925);
DISPLAY 1.595745 (-5275 1925);
PAINT GREEN (-5275 1925);
DISPLAY INVISIBLE (-5275 1925);
FORCEPROP 1 LAST BODY_TYPE PLUMBING
J 0
(-5600 2000);
DISPLAY 1.595745 (-5600 2000);
PAINT GREEN (-5600 2000);
DISPLAY INVISIBLE (-5600 2000);
FORCEPROP 2 LAST CDS_LIB mstr_standard
J 0
(-5600 2050);
PAINT MONO (-5600 2050);
DISPLAY INVISIBLE (-5600 2050);
FORCEADD TAP..6
(-5600 2100);
FORCEPROP 3 LASTPIN (-5550 2100) SIG_NAME M_M_DQ<12>
J 0
(-5540 2110);
DISPLAY 0.659574 (-5540 2110);
PAINT MONO (-5540 2110);
DISPLAY INVISIBLE (-5540 2110);
FORCEPROP 1 LASTPIN (-5550 2100) BN 12
J 0
(-5602 2108);
DISPLAY 0.617021 (-5602 2108);
PAINT GREEN (-5602 2108);
FORCEPROP 1 LAST PATH I34
J 0
(-5602 2100);
DISPLAY 0.872340 (-5602 2100);
PAINT GREEN (-5602 2100);
DISPLAY INVISIBLE (-5602 2100);
FORCEPROP 1 LAST HDL_TAP TRUE
J 0
(-5275 1975);
DISPLAY 1.595745 (-5275 1975);
PAINT GREEN (-5275 1975);
DISPLAY INVISIBLE (-5275 1975);
FORCEPROP 1 LAST BODY_TYPE PLUMBING
J 0
(-5600 2050);
DISPLAY 1.595745 (-5600 2050);
PAINT GREEN (-5600 2050);
DISPLAY INVISIBLE (-5600 2050);
FORCEPROP 2 LAST CDS_LIB mstr_standard
J 0
(-5600 2100);
PAINT MONO (-5600 2100);
DISPLAY INVISIBLE (-5600 2100);
FORCEADD TAP..6
(-5600 2150);
FORCEPROP 3 LASTPIN (-5550 2150) SIG_NAME M_M_DQ<13>
J 0
(-5540 2160);
DISPLAY 0.659574 (-5540 2160);
PAINT MONO (-5540 2160);
DISPLAY INVISIBLE (-5540 2160);
FORCEPROP 1 LASTPIN (-5550 2150) BN 13
J 0
(-5602 2158);
DISPLAY 0.617021 (-5602 2158);
PAINT GREEN (-5602 2158);
FORCEPROP 1 LAST PATH I35
J 0
(-5602 2150);
DISPLAY 0.872340 (-5602 2150);
PAINT GREEN (-5602 2150);
DISPLAY INVISIBLE (-5602 2150);
FORCEPROP 1 LAST HDL_TAP TRUE
J 0
(-5275 2025);
DISPLAY 1.595745 (-5275 2025);
PAINT GREEN (-5275 2025);
DISPLAY INVISIBLE (-5275 2025);
FORCEPROP 1 LAST BODY_TYPE PLUMBING
J 0
(-5600 2100);
DISPLAY 1.595745 (-5600 2100);
PAINT GREEN (-5600 2100);
DISPLAY INVISIBLE (-5600 2100);
FORCEPROP 2 LAST CDS_LIB mstr_standard
J 0
(-5600 2150);
PAINT MONO (-5600 2150);
DISPLAY INVISIBLE (-5600 2150);
FORCEADD TAP..6
(-5600 2200);
FORCEPROP 3 LASTPIN (-5550 2200) SIG_NAME M_M_DQ<14>
J 0
(-5540 2210);
DISPLAY 0.659574 (-5540 2210);
PAINT MONO (-5540 2210);
DISPLAY INVISIBLE (-5540 2210);
FORCEPROP 1 LASTPIN (-5550 2200) BN 14
J 0
(-5602 2208);
DISPLAY 0.617021 (-5602 2208);
PAINT GREEN (-5602 2208);
FORCEPROP 1 LAST PATH I36
J 0
(-5602 2200);
DISPLAY 0.872340 (-5602 2200);
PAINT GREEN (-5602 2200);
DISPLAY INVISIBLE (-5602 2200);
FORCEPROP 1 LAST HDL_TAP TRUE
J 0
(-5275 2075);
DISPLAY 1.595745 (-5275 2075);
PAINT GREEN (-5275 2075);
DISPLAY INVISIBLE (-5275 2075);
FORCEPROP 1 LAST BODY_TYPE PLUMBING
J 0
(-5600 2150);
DISPLAY 1.595745 (-5600 2150);
PAINT GREEN (-5600 2150);
DISPLAY INVISIBLE (-5600 2150);
FORCEPROP 2 LAST CDS_LIB mstr_standard
J 0
(-5600 2200);
PAINT MONO (-5600 2200);
DISPLAY INVISIBLE (-5600 2200);
FORCEADD TAP..6
(-5600 2250);
FORCEPROP 3 LASTPIN (-5550 2250) SIG_NAME M_M_DQ<15>
J 0
(-5540 2260);
DISPLAY 0.659574 (-5540 2260);
PAINT MONO (-5540 2260);
DISPLAY INVISIBLE (-5540 2260);
FORCEPROP 1 LASTPIN (-5550 2250) BN 15
J 0
(-5602 2258);
DISPLAY 0.617021 (-5602 2258);
PAINT GREEN (-5602 2258);
FORCEPROP 1 LAST PATH I37
J 0
(-5602 2250);
DISPLAY 0.872340 (-5602 2250);
PAINT GREEN (-5602 2250);
DISPLAY INVISIBLE (-5602 2250);
FORCEPROP 1 LAST HDL_TAP TRUE
J 0
(-5275 2125);
DISPLAY 1.595745 (-5275 2125);
PAINT GREEN (-5275 2125);
DISPLAY INVISIBLE (-5275 2125);
FORCEPROP 1 LAST BODY_TYPE PLUMBING
J 0
(-5600 2200);
DISPLAY 1.595745 (-5600 2200);
PAINT GREEN (-5600 2200);
DISPLAY INVISIBLE (-5600 2200);
FORCEPROP 2 LAST CDS_LIB mstr_standard
J 0
(-5600 2250);
PAINT MONO (-5600 2250);
DISPLAY INVISIBLE (-5600 2250);
FORCEADD TAP..6
(-5600 2300);
FORCEPROP 3 LASTPIN (-5550 2300) SIG_NAME M_M_DQ<16>
J 0
(-5540 2310);
DISPLAY 0.659574 (-5540 2310);
PAINT MONO (-5540 2310);
DISPLAY INVISIBLE (-5540 2310);
FORCEPROP 1 LASTPIN (-5550 2300) BN 16
J 0
(-5602 2308);
DISPLAY 0.617021 (-5602 2308);
PAINT GREEN (-5602 2308);
FORCEPROP 1 LAST PATH I38
J 0
(-5602 2300);
DISPLAY 0.872340 (-5602 2300);
PAINT GREEN (-5602 2300);
DISPLAY INVISIBLE (-5602 2300);
FORCEPROP 1 LAST HDL_TAP TRUE
J 0
(-5275 2175);
DISPLAY 1.595745 (-5275 2175);
PAINT GREEN (-5275 2175);
DISPLAY INVISIBLE (-5275 2175);
FORCEPROP 1 LAST BODY_TYPE PLUMBING
J 0
(-5600 2250);
DISPLAY 1.595745 (-5600 2250);
PAINT GREEN (-5600 2250);
DISPLAY INVISIBLE (-5600 2250);
FORCEPROP 2 LAST CDS_LIB mstr_standard
J 0
(-5600 2300);
PAINT MONO (-5600 2300);
DISPLAY INVISIBLE (-5600 2300);
FORCEADD TAP..6
(-5600 2350);
FORCEPROP 3 LASTPIN (-5550 2350) SIG_NAME M_M_DQ<17>
J 0
(-5540 2360);
DISPLAY 0.659574 (-5540 2360);
PAINT MONO (-5540 2360);
DISPLAY INVISIBLE (-5540 2360);
FORCEPROP 1 LASTPIN (-5550 2350) BN 17
J 0
(-5602 2358);
DISPLAY 0.617021 (-5602 2358);
PAINT GREEN (-5602 2358);
FORCEPROP 1 LAST PATH I39
J 0
(-5602 2350);
DISPLAY 0.872340 (-5602 2350);
PAINT GREEN (-5602 2350);
DISPLAY INVISIBLE (-5602 2350);
FORCEPROP 1 LAST HDL_TAP TRUE
J 0
(-5275 2225);
DISPLAY 1.595745 (-5275 2225);
PAINT GREEN (-5275 2225);
DISPLAY INVISIBLE (-5275 2225);
FORCEPROP 1 LAST BODY_TYPE PLUMBING
J 0
(-5600 2300);
DISPLAY 1.595745 (-5600 2300);
PAINT GREEN (-5600 2300);
DISPLAY INVISIBLE (-5600 2300);
FORCEPROP 2 LAST CDS_LIB mstr_standard
J 0
(-5600 2350);
PAINT MONO (-5600 2350);
DISPLAY INVISIBLE (-5600 2350);
FORCEADD OFFPAGE..6
(-6450 1450);
FORCEPROP 2 LAST $XR1 88 
J 0
(-6789 1450);
DISPLAY 0.638298 (-6789 1450);
PAINT MONO (-6789 1450);
FORCEPROP 2 LAST $XR0 87 
J 0
(-6699 1450);
DISPLAY 0.638298 (-6699 1450);
PAINT MONO (-6699 1450);
FORCEPROP 2 LAST PATH I4
J 0
(-6400 1525);
DISPLAY 1.021277 (-6400 1525);
PAINT ORANGE (-6400 1525);
DISPLAY INVISIBLE (-6400 1525);
FORCEPROP 1 LAST COMMENT_BODY TRUE
J 0
(-6350 1375);
DISPLAY 1.170213 (-6350 1375);
PAINT GREEN (-6350 1375);
DISPLAY INVISIBLE (-6350 1375);
FORCEPROP 1 LAST OFFPAGE TRUE
J 0
(-6125 1325);
DISPLAY 1.170213 (-6125 1325);
PAINT GREEN (-6125 1325);
DISPLAY INVISIBLE (-6125 1325);
FORCEPROP 2 LAST CDS_LIB mstr_standard
J 0
(-6450 1450);
PAINT MONO (-6450 1450);
DISPLAY INVISIBLE (-6450 1450);
FORCEADD TAP..6
(-5600 2400);
FORCEPROP 3 LASTPIN (-5550 2400) SIG_NAME M_M_DQ<18>
J 0
(-5540 2410);
DISPLAY 0.659574 (-5540 2410);
PAINT MONO (-5540 2410);
DISPLAY INVISIBLE (-5540 2410);
FORCEPROP 1 LASTPIN (-5550 2400) BN 18
J 0
(-5602 2408);
DISPLAY 0.617021 (-5602 2408);
PAINT GREEN (-5602 2408);
FORCEPROP 1 LAST PATH I40
J 0
(-5602 2400);
DISPLAY 0.872340 (-5602 2400);
PAINT GREEN (-5602 2400);
DISPLAY INVISIBLE (-5602 2400);
FORCEPROP 1 LAST HDL_TAP TRUE
J 0
(-5275 2275);
DISPLAY 1.595745 (-5275 2275);
PAINT GREEN (-5275 2275);
DISPLAY INVISIBLE (-5275 2275);
FORCEPROP 1 LAST BODY_TYPE PLUMBING
J 0
(-5600 2350);
DISPLAY 1.595745 (-5600 2350);
PAINT GREEN (-5600 2350);
DISPLAY INVISIBLE (-5600 2350);
FORCEPROP 2 LAST CDS_LIB mstr_standard
J 0
(-5600 2400);
PAINT MONO (-5600 2400);
DISPLAY INVISIBLE (-5600 2400);
FORCEADD TAP..6
(-5600 2450);
FORCEPROP 3 LASTPIN (-5550 2450) SIG_NAME M_M_DQ<19>
J 0
(-5540 2460);
DISPLAY 0.659574 (-5540 2460);
PAINT MONO (-5540 2460);
DISPLAY INVISIBLE (-5540 2460);
FORCEPROP 1 LASTPIN (-5550 2450) BN 19
J 0
(-5602 2458);
DISPLAY 0.617021 (-5602 2458);
PAINT GREEN (-5602 2458);
FORCEPROP 1 LAST PATH I41
J 0
(-5602 2450);
DISPLAY 0.872340 (-5602 2450);
PAINT GREEN (-5602 2450);
DISPLAY INVISIBLE (-5602 2450);
FORCEPROP 1 LAST HDL_TAP TRUE
J 0
(-5275 2325);
DISPLAY 1.595745 (-5275 2325);
PAINT GREEN (-5275 2325);
DISPLAY INVISIBLE (-5275 2325);
FORCEPROP 1 LAST BODY_TYPE PLUMBING
J 0
(-5600 2400);
DISPLAY 1.595745 (-5600 2400);
PAINT GREEN (-5600 2400);
DISPLAY INVISIBLE (-5600 2400);
FORCEPROP 2 LAST CDS_LIB mstr_standard
J 0
(-5600 2450);
PAINT MONO (-5600 2450);
DISPLAY INVISIBLE (-5600 2450);
FORCEADD TAP..6
(-5600 2500);
FORCEPROP 3 LASTPIN (-5550 2500) SIG_NAME M_M_DQ<20>
J 0
(-5540 2510);
DISPLAY 0.659574 (-5540 2510);
PAINT MONO (-5540 2510);
DISPLAY INVISIBLE (-5540 2510);
FORCEPROP 1 LASTPIN (-5550 2500) BN 20
J 0
(-5602 2508);
DISPLAY 0.617021 (-5602 2508);
PAINT GREEN (-5602 2508);
FORCEPROP 1 LAST PATH I42
J 0
(-5602 2500);
DISPLAY 0.872340 (-5602 2500);
PAINT GREEN (-5602 2500);
DISPLAY INVISIBLE (-5602 2500);
FORCEPROP 1 LAST HDL_TAP TRUE
J 0
(-5275 2375);
DISPLAY 1.595745 (-5275 2375);
PAINT GREEN (-5275 2375);
DISPLAY INVISIBLE (-5275 2375);
FORCEPROP 1 LAST BODY_TYPE PLUMBING
J 0
(-5600 2450);
DISPLAY 1.595745 (-5600 2450);
PAINT GREEN (-5600 2450);
DISPLAY INVISIBLE (-5600 2450);
FORCEPROP 2 LAST CDS_LIB mstr_standard
J 0
(-5600 2500);
PAINT MONO (-5600 2500);
DISPLAY INVISIBLE (-5600 2500);
FORCEADD TAP..6
(-5600 2550);
FORCEPROP 3 LASTPIN (-5550 2550) SIG_NAME M_M_DQ<21>
J 0
(-5540 2560);
DISPLAY 0.659574 (-5540 2560);
PAINT MONO (-5540 2560);
DISPLAY INVISIBLE (-5540 2560);
FORCEPROP 1 LASTPIN (-5550 2550) BN 21
J 0
(-5602 2558);
DISPLAY 0.617021 (-5602 2558);
PAINT GREEN (-5602 2558);
FORCEPROP 1 LAST PATH I43
J 0
(-5602 2550);
DISPLAY 0.872340 (-5602 2550);
PAINT GREEN (-5602 2550);
DISPLAY INVISIBLE (-5602 2550);
FORCEPROP 1 LAST HDL_TAP TRUE
J 0
(-5275 2425);
DISPLAY 1.595745 (-5275 2425);
PAINT GREEN (-5275 2425);
DISPLAY INVISIBLE (-5275 2425);
FORCEPROP 1 LAST BODY_TYPE PLUMBING
J 0
(-5600 2500);
DISPLAY 1.595745 (-5600 2500);
PAINT GREEN (-5600 2500);
DISPLAY INVISIBLE (-5600 2500);
FORCEPROP 2 LAST CDS_LIB mstr_standard
J 0
(-5600 2550);
PAINT MONO (-5600 2550);
DISPLAY INVISIBLE (-5600 2550);
FORCEADD TAP..6
(-5600 2600);
FORCEPROP 3 LASTPIN (-5550 2600) SIG_NAME M_M_DQ<22>
J 0
(-5540 2610);
DISPLAY 0.659574 (-5540 2610);
PAINT MONO (-5540 2610);
DISPLAY INVISIBLE (-5540 2610);
FORCEPROP 1 LASTPIN (-5550 2600) BN 22
J 0
(-5602 2608);
DISPLAY 0.617021 (-5602 2608);
PAINT GREEN (-5602 2608);
FORCEPROP 1 LAST PATH I44
J 0
(-5602 2600);
DISPLAY 0.872340 (-5602 2600);
PAINT GREEN (-5602 2600);
DISPLAY INVISIBLE (-5602 2600);
FORCEPROP 1 LAST HDL_TAP TRUE
J 0
(-5275 2475);
DISPLAY 1.595745 (-5275 2475);
PAINT GREEN (-5275 2475);
DISPLAY INVISIBLE (-5275 2475);
FORCEPROP 1 LAST BODY_TYPE PLUMBING
J 0
(-5600 2550);
DISPLAY 1.595745 (-5600 2550);
PAINT GREEN (-5600 2550);
DISPLAY INVISIBLE (-5600 2550);
FORCEPROP 2 LAST CDS_LIB mstr_standard
J 0
(-5600 2600);
PAINT MONO (-5600 2600);
DISPLAY INVISIBLE (-5600 2600);
FORCEADD TAP..6
(-5600 2650);
FORCEPROP 3 LASTPIN (-5550 2650) SIG_NAME M_M_DQ<23>
J 0
(-5540 2660);
DISPLAY 0.659574 (-5540 2660);
PAINT MONO (-5540 2660);
DISPLAY INVISIBLE (-5540 2660);
FORCEPROP 1 LASTPIN (-5550 2650) BN 23
J 0
(-5602 2658);
DISPLAY 0.617021 (-5602 2658);
PAINT GREEN (-5602 2658);
FORCEPROP 1 LAST PATH I45
J 0
(-5602 2650);
DISPLAY 0.872340 (-5602 2650);
PAINT GREEN (-5602 2650);
DISPLAY INVISIBLE (-5602 2650);
FORCEPROP 1 LAST HDL_TAP TRUE
J 0
(-5275 2525);
DISPLAY 1.595745 (-5275 2525);
PAINT GREEN (-5275 2525);
DISPLAY INVISIBLE (-5275 2525);
FORCEPROP 1 LAST BODY_TYPE PLUMBING
J 0
(-5600 2600);
DISPLAY 1.595745 (-5600 2600);
PAINT GREEN (-5600 2600);
DISPLAY INVISIBLE (-5600 2600);
FORCEPROP 2 LAST CDS_LIB mstr_standard
J 0
(-5600 2650);
PAINT MONO (-5600 2650);
DISPLAY INVISIBLE (-5600 2650);
FORCEADD TAP..6
(-5600 2700);
FORCEPROP 3 LASTPIN (-5550 2700) SIG_NAME M_M_DQ<24>
J 0
(-5540 2710);
DISPLAY 0.659574 (-5540 2710);
PAINT MONO (-5540 2710);
DISPLAY INVISIBLE (-5540 2710);
FORCEPROP 1 LASTPIN (-5550 2700) BN 24
J 0
(-5602 2708);
DISPLAY 0.617021 (-5602 2708);
PAINT GREEN (-5602 2708);
FORCEPROP 1 LAST PATH I46
J 0
(-5602 2700);
DISPLAY 0.872340 (-5602 2700);
PAINT GREEN (-5602 2700);
DISPLAY INVISIBLE (-5602 2700);
FORCEPROP 1 LAST HDL_TAP TRUE
J 0
(-5275 2575);
DISPLAY 1.595745 (-5275 2575);
PAINT GREEN (-5275 2575);
DISPLAY INVISIBLE (-5275 2575);
FORCEPROP 1 LAST BODY_TYPE PLUMBING
J 0
(-5600 2650);
DISPLAY 1.595745 (-5600 2650);
PAINT GREEN (-5600 2650);
DISPLAY INVISIBLE (-5600 2650);
FORCEPROP 2 LAST CDS_LIB mstr_standard
J 0
(-5600 2700);
PAINT MONO (-5600 2700);
DISPLAY INVISIBLE (-5600 2700);
FORCEADD TAP..6
(-5600 2800);
FORCEPROP 3 LASTPIN (-5550 2800) SIG_NAME M_M_DQ<26>
J 0
(-5540 2810);
DISPLAY 0.659574 (-5540 2810);
PAINT MONO (-5540 2810);
DISPLAY INVISIBLE (-5540 2810);
FORCEPROP 1 LASTPIN (-5550 2800) BN 26
J 0
(-5602 2808);
DISPLAY 0.617021 (-5602 2808);
PAINT GREEN (-5602 2808);
FORCEPROP 1 LAST PATH I47
J 0
(-5602 2800);
DISPLAY 0.872340 (-5602 2800);
PAINT GREEN (-5602 2800);
DISPLAY INVISIBLE (-5602 2800);
FORCEPROP 1 LAST HDL_TAP TRUE
J 0
(-5275 2675);
DISPLAY 1.595745 (-5275 2675);
PAINT GREEN (-5275 2675);
DISPLAY INVISIBLE (-5275 2675);
FORCEPROP 1 LAST BODY_TYPE PLUMBING
J 0
(-5600 2750);
DISPLAY 1.595745 (-5600 2750);
PAINT GREEN (-5600 2750);
DISPLAY INVISIBLE (-5600 2750);
FORCEPROP 2 LAST CDS_LIB mstr_standard
J 0
(-5600 2800);
PAINT MONO (-5600 2800);
DISPLAY INVISIBLE (-5600 2800);
FORCEADD TAP..6
(-5600 2750);
FORCEPROP 3 LASTPIN (-5550 2750) SIG_NAME M_M_DQ<25>
J 0
(-5540 2760);
DISPLAY 0.659574 (-5540 2760);
PAINT MONO (-5540 2760);
DISPLAY INVISIBLE (-5540 2760);
FORCEPROP 1 LASTPIN (-5550 2750) BN 25
J 0
(-5602 2758);
DISPLAY 0.617021 (-5602 2758);
PAINT GREEN (-5602 2758);
FORCEPROP 1 LAST PATH I48
J 0
(-5602 2750);
DISPLAY 0.872340 (-5602 2750);
PAINT GREEN (-5602 2750);
DISPLAY INVISIBLE (-5602 2750);
FORCEPROP 1 LAST HDL_TAP TRUE
J 0
(-5275 2625);
DISPLAY 1.595745 (-5275 2625);
PAINT GREEN (-5275 2625);
DISPLAY INVISIBLE (-5275 2625);
FORCEPROP 1 LAST BODY_TYPE PLUMBING
J 0
(-5600 2700);
DISPLAY 1.595745 (-5600 2700);
PAINT GREEN (-5600 2700);
DISPLAY INVISIBLE (-5600 2700);
FORCEPROP 2 LAST CDS_LIB mstr_standard
J 0
(-5600 2750);
PAINT MONO (-5600 2750);
DISPLAY INVISIBLE (-5600 2750);
FORCEADD TAP..6
(-5600 2850);
FORCEPROP 3 LASTPIN (-5550 2850) SIG_NAME M_M_DQ<27>
J 0
(-5540 2860);
DISPLAY 0.659574 (-5540 2860);
PAINT MONO (-5540 2860);
DISPLAY INVISIBLE (-5540 2860);
FORCEPROP 1 LASTPIN (-5550 2850) BN 27
J 0
(-5602 2858);
DISPLAY 0.617021 (-5602 2858);
PAINT GREEN (-5602 2858);
FORCEPROP 1 LAST PATH I49
J 0
(-5602 2850);
DISPLAY 0.872340 (-5602 2850);
PAINT GREEN (-5602 2850);
DISPLAY INVISIBLE (-5602 2850);
FORCEPROP 1 LAST HDL_TAP TRUE
J 0
(-5275 2725);
DISPLAY 1.595745 (-5275 2725);
PAINT GREEN (-5275 2725);
DISPLAY INVISIBLE (-5275 2725);
FORCEPROP 1 LAST BODY_TYPE PLUMBING
J 0
(-5600 2800);
DISPLAY 1.595745 (-5600 2800);
PAINT GREEN (-5600 2800);
DISPLAY INVISIBLE (-5600 2800);
FORCEPROP 2 LAST CDS_LIB mstr_standard
J 0
(-5600 2850);
PAINT MONO (-5600 2850);
DISPLAY INVISIBLE (-5600 2850);
FORCEADD TAP..6
(-5600 600);
FORCEPROP 3 LASTPIN (-5550 600) SIG_NAME M_M_CLK_DN<0>
J 0
(-5540 610);
DISPLAY 0.659574 (-5540 610);
PAINT MONO (-5540 610);
DISPLAY INVISIBLE (-5540 610);
FORCEPROP 1 LASTPIN (-5550 600) BN 0
J 0
(-5602 608);
DISPLAY 0.617021 (-5602 608);
PAINT GREEN (-5602 608);
FORCEPROP 1 LAST PATH I5
J 0
(-5602 600);
DISPLAY 0.872340 (-5602 600);
PAINT GREEN (-5602 600);
DISPLAY INVISIBLE (-5602 600);
FORCEPROP 1 LAST HDL_TAP TRUE
J 0
(-5275 475);
DISPLAY 1.595745 (-5275 475);
PAINT GREEN (-5275 475);
DISPLAY INVISIBLE (-5275 475);
FORCEPROP 1 LAST BODY_TYPE PLUMBING
J 0
(-5600 550);
DISPLAY 1.595745 (-5600 550);
PAINT GREEN (-5600 550);
DISPLAY INVISIBLE (-5600 550);
FORCEPROP 2 LAST CDS_LIB mstr_standard
J 0
(-5600 600);
PAINT MONO (-5600 600);
DISPLAY INVISIBLE (-5600 600);
FORCEADD TAP..6
(-5600 2900);
FORCEPROP 3 LASTPIN (-5550 2900) SIG_NAME M_M_DQ<28>
J 0
(-5540 2910);
DISPLAY 0.659574 (-5540 2910);
PAINT MONO (-5540 2910);
DISPLAY INVISIBLE (-5540 2910);
FORCEPROP 1 LASTPIN (-5550 2900) BN 28
J 0
(-5602 2908);
DISPLAY 0.617021 (-5602 2908);
PAINT GREEN (-5602 2908);
FORCEPROP 1 LAST PATH I50
J 0
(-5602 2900);
DISPLAY 0.872340 (-5602 2900);
PAINT GREEN (-5602 2900);
DISPLAY INVISIBLE (-5602 2900);
FORCEPROP 1 LAST HDL_TAP TRUE
J 0
(-5275 2775);
DISPLAY 1.595745 (-5275 2775);
PAINT GREEN (-5275 2775);
DISPLAY INVISIBLE (-5275 2775);
FORCEPROP 1 LAST BODY_TYPE PLUMBING
J 0
(-5600 2850);
DISPLAY 1.595745 (-5600 2850);
PAINT GREEN (-5600 2850);
DISPLAY INVISIBLE (-5600 2850);
FORCEPROP 2 LAST CDS_LIB mstr_standard
J 0
(-5600 2900);
PAINT MONO (-5600 2900);
DISPLAY INVISIBLE (-5600 2900);
FORCEADD TAP..6
(-5600 2950);
FORCEPROP 3 LASTPIN (-5550 2950) SIG_NAME M_M_DQ<29>
J 0
(-5540 2960);
DISPLAY 0.659574 (-5540 2960);
PAINT MONO (-5540 2960);
DISPLAY INVISIBLE (-5540 2960);
FORCEPROP 1 LASTPIN (-5550 2950) BN 29
J 0
(-5602 2958);
DISPLAY 0.617021 (-5602 2958);
PAINT GREEN (-5602 2958);
FORCEPROP 1 LAST PATH I51
J 0
(-5602 2950);
DISPLAY 0.872340 (-5602 2950);
PAINT GREEN (-5602 2950);
DISPLAY INVISIBLE (-5602 2950);
FORCEPROP 1 LAST HDL_TAP TRUE
J 0
(-5275 2825);
DISPLAY 1.595745 (-5275 2825);
PAINT GREEN (-5275 2825);
DISPLAY INVISIBLE (-5275 2825);
FORCEPROP 1 LAST BODY_TYPE PLUMBING
J 0
(-5600 2900);
DISPLAY 1.595745 (-5600 2900);
PAINT GREEN (-5600 2900);
DISPLAY INVISIBLE (-5600 2900);
FORCEPROP 2 LAST CDS_LIB mstr_standard
J 0
(-5600 2950);
PAINT MONO (-5600 2950);
DISPLAY INVISIBLE (-5600 2950);
FORCEADD TAP..6
(-5600 3050);
FORCEPROP 3 LASTPIN (-5550 3050) SIG_NAME M_M_DQ<31>
J 0
(-5540 3060);
DISPLAY 0.659574 (-5540 3060);
PAINT MONO (-5540 3060);
DISPLAY INVISIBLE (-5540 3060);
FORCEPROP 1 LASTPIN (-5550 3050) BN 31
J 0
(-5602 3058);
DISPLAY 0.617021 (-5602 3058);
PAINT GREEN (-5602 3058);
FORCEPROP 1 LAST PATH I52
J 0
(-5602 3050);
DISPLAY 0.872340 (-5602 3050);
PAINT GREEN (-5602 3050);
DISPLAY INVISIBLE (-5602 3050);
FORCEPROP 1 LAST HDL_TAP TRUE
J 0
(-5275 2925);
DISPLAY 1.595745 (-5275 2925);
PAINT GREEN (-5275 2925);
DISPLAY INVISIBLE (-5275 2925);
FORCEPROP 1 LAST BODY_TYPE PLUMBING
J 0
(-5600 3000);
DISPLAY 1.595745 (-5600 3000);
PAINT GREEN (-5600 3000);
DISPLAY INVISIBLE (-5600 3000);
FORCEPROP 2 LAST CDS_LIB mstr_standard
J 0
(-5600 3050);
PAINT MONO (-5600 3050);
DISPLAY INVISIBLE (-5600 3050);
FORCEADD TAP..6
(-5600 3000);
FORCEPROP 3 LASTPIN (-5550 3000) SIG_NAME M_M_DQ<30>
J 0
(-5540 3010);
DISPLAY 0.659574 (-5540 3010);
PAINT MONO (-5540 3010);
DISPLAY INVISIBLE (-5540 3010);
FORCEPROP 1 LASTPIN (-5550 3000) BN 30
J 0
(-5602 3008);
DISPLAY 0.617021 (-5602 3008);
PAINT GREEN (-5602 3008);
FORCEPROP 1 LAST PATH I53
J 0
(-5602 3000);
DISPLAY 0.872340 (-5602 3000);
PAINT GREEN (-5602 3000);
DISPLAY INVISIBLE (-5602 3000);
FORCEPROP 1 LAST HDL_TAP TRUE
J 0
(-5275 2875);
DISPLAY 1.595745 (-5275 2875);
PAINT GREEN (-5275 2875);
DISPLAY INVISIBLE (-5275 2875);
FORCEPROP 1 LAST BODY_TYPE PLUMBING
J 0
(-5600 2950);
DISPLAY 1.595745 (-5600 2950);
PAINT GREEN (-5600 2950);
DISPLAY INVISIBLE (-5600 2950);
FORCEPROP 2 LAST CDS_LIB mstr_standard
J 0
(-5600 3000);
PAINT MONO (-5600 3000);
DISPLAY INVISIBLE (-5600 3000);
FORCEADD TAP..6
(-5600 3100);
FORCEPROP 3 LASTPIN (-5550 3100) SIG_NAME M_M_DQ<32>
J 0
(-5540 3110);
DISPLAY 0.659574 (-5540 3110);
PAINT MONO (-5540 3110);
DISPLAY INVISIBLE (-5540 3110);
FORCEPROP 1 LASTPIN (-5550 3100) BN 32
J 0
(-5602 3108);
DISPLAY 0.617021 (-5602 3108);
PAINT GREEN (-5602 3108);
FORCEPROP 1 LAST PATH I54
J 0
(-5602 3100);
DISPLAY 0.872340 (-5602 3100);
PAINT GREEN (-5602 3100);
DISPLAY INVISIBLE (-5602 3100);
FORCEPROP 1 LAST HDL_TAP TRUE
J 0
(-5275 2975);
DISPLAY 1.595745 (-5275 2975);
PAINT GREEN (-5275 2975);
DISPLAY INVISIBLE (-5275 2975);
FORCEPROP 1 LAST BODY_TYPE PLUMBING
J 0
(-5600 3050);
DISPLAY 1.595745 (-5600 3050);
PAINT GREEN (-5600 3050);
DISPLAY INVISIBLE (-5600 3050);
FORCEPROP 2 LAST CDS_LIB mstr_standard
J 0
(-5600 3100);
PAINT MONO (-5600 3100);
DISPLAY INVISIBLE (-5600 3100);
FORCEADD TAP..6
(-5600 3150);
FORCEPROP 3 LASTPIN (-5550 3150) SIG_NAME M_M_DQ<33>
J 0
(-5540 3160);
DISPLAY 0.659574 (-5540 3160);
PAINT MONO (-5540 3160);
DISPLAY INVISIBLE (-5540 3160);
FORCEPROP 1 LASTPIN (-5550 3150) BN 33
J 0
(-5602 3158);
DISPLAY 0.617021 (-5602 3158);
PAINT GREEN (-5602 3158);
FORCEPROP 1 LAST PATH I55
J 0
(-5602 3150);
DISPLAY 0.872340 (-5602 3150);
PAINT GREEN (-5602 3150);
DISPLAY INVISIBLE (-5602 3150);
FORCEPROP 1 LAST HDL_TAP TRUE
J 0
(-5275 3025);
DISPLAY 1.595745 (-5275 3025);
PAINT GREEN (-5275 3025);
DISPLAY INVISIBLE (-5275 3025);
FORCEPROP 1 LAST BODY_TYPE PLUMBING
J 0
(-5600 3100);
DISPLAY 1.595745 (-5600 3100);
PAINT GREEN (-5600 3100);
DISPLAY INVISIBLE (-5600 3100);
FORCEPROP 2 LAST CDS_LIB mstr_standard
J 0
(-5600 3150);
PAINT MONO (-5600 3150);
DISPLAY INVISIBLE (-5600 3150);
FORCEADD TAP..6
(-5600 3200);
FORCEPROP 3 LASTPIN (-5550 3200) SIG_NAME M_M_DQ<34>
J 0
(-5540 3210);
DISPLAY 0.659574 (-5540 3210);
PAINT MONO (-5540 3210);
DISPLAY INVISIBLE (-5540 3210);
FORCEPROP 1 LASTPIN (-5550 3200) BN 34
J 0
(-5602 3208);
DISPLAY 0.617021 (-5602 3208);
PAINT GREEN (-5602 3208);
FORCEPROP 1 LAST PATH I56
J 0
(-5602 3200);
DISPLAY 0.872340 (-5602 3200);
PAINT GREEN (-5602 3200);
DISPLAY INVISIBLE (-5602 3200);
FORCEPROP 1 LAST HDL_TAP TRUE
J 0
(-5275 3075);
DISPLAY 1.595745 (-5275 3075);
PAINT GREEN (-5275 3075);
DISPLAY INVISIBLE (-5275 3075);
FORCEPROP 1 LAST BODY_TYPE PLUMBING
J 0
(-5600 3150);
DISPLAY 1.595745 (-5600 3150);
PAINT GREEN (-5600 3150);
DISPLAY INVISIBLE (-5600 3150);
FORCEPROP 2 LAST CDS_LIB mstr_standard
J 0
(-5600 3200);
PAINT MONO (-5600 3200);
DISPLAY INVISIBLE (-5600 3200);
FORCEADD TAP..6
(-5600 3300);
FORCEPROP 3 LASTPIN (-5550 3300) SIG_NAME M_M_DQ<36>
J 0
(-5540 3310);
DISPLAY 0.659574 (-5540 3310);
PAINT MONO (-5540 3310);
DISPLAY INVISIBLE (-5540 3310);
FORCEPROP 1 LASTPIN (-5550 3300) BN 36
J 0
(-5602 3308);
DISPLAY 0.617021 (-5602 3308);
PAINT GREEN (-5602 3308);
FORCEPROP 1 LAST PATH I57
J 0
(-5602 3300);
DISPLAY 0.872340 (-5602 3300);
PAINT GREEN (-5602 3300);
DISPLAY INVISIBLE (-5602 3300);
FORCEPROP 1 LAST HDL_TAP TRUE
J 0
(-5275 3175);
DISPLAY 1.595745 (-5275 3175);
PAINT GREEN (-5275 3175);
DISPLAY INVISIBLE (-5275 3175);
FORCEPROP 1 LAST BODY_TYPE PLUMBING
J 0
(-5600 3250);
DISPLAY 1.595745 (-5600 3250);
PAINT GREEN (-5600 3250);
DISPLAY INVISIBLE (-5600 3250);
FORCEPROP 2 LAST CDS_LIB mstr_standard
J 0
(-5600 3300);
PAINT MONO (-5600 3300);
DISPLAY INVISIBLE (-5600 3300);
FORCEADD TAP..6
(-5600 3250);
FORCEPROP 3 LASTPIN (-5550 3250) SIG_NAME M_M_DQ<35>
J 0
(-5540 3260);
DISPLAY 0.659574 (-5540 3260);
PAINT MONO (-5540 3260);
DISPLAY INVISIBLE (-5540 3260);
FORCEPROP 1 LASTPIN (-5550 3250) BN 35
J 0
(-5602 3258);
DISPLAY 0.617021 (-5602 3258);
PAINT GREEN (-5602 3258);
FORCEPROP 1 LAST PATH I58
J 0
(-5602 3250);
DISPLAY 0.872340 (-5602 3250);
PAINT GREEN (-5602 3250);
DISPLAY INVISIBLE (-5602 3250);
FORCEPROP 1 LAST HDL_TAP TRUE
J 0
(-5275 3125);
DISPLAY 1.595745 (-5275 3125);
PAINT GREEN (-5275 3125);
DISPLAY INVISIBLE (-5275 3125);
FORCEPROP 1 LAST BODY_TYPE PLUMBING
J 0
(-5600 3200);
DISPLAY 1.595745 (-5600 3200);
PAINT GREEN (-5600 3200);
DISPLAY INVISIBLE (-5600 3200);
FORCEPROP 2 LAST CDS_LIB mstr_standard
J 0
(-5600 3250);
PAINT MONO (-5600 3250);
DISPLAY INVISIBLE (-5600 3250);
FORCEADD TAP..6
(-5600 3350);
FORCEPROP 3 LASTPIN (-5550 3350) SIG_NAME M_M_DQ<37>
J 0
(-5540 3360);
DISPLAY 0.659574 (-5540 3360);
PAINT MONO (-5540 3360);
DISPLAY INVISIBLE (-5540 3360);
FORCEPROP 1 LASTPIN (-5550 3350) BN 37
J 0
(-5602 3358);
DISPLAY 0.617021 (-5602 3358);
PAINT GREEN (-5602 3358);
FORCEPROP 1 LAST PATH I59
J 0
(-5602 3350);
DISPLAY 0.872340 (-5602 3350);
PAINT GREEN (-5602 3350);
DISPLAY INVISIBLE (-5602 3350);
FORCEPROP 1 LAST HDL_TAP TRUE
J 0
(-5275 3225);
DISPLAY 1.595745 (-5275 3225);
PAINT GREEN (-5275 3225);
DISPLAY INVISIBLE (-5275 3225);
FORCEPROP 1 LAST BODY_TYPE PLUMBING
J 0
(-5600 3300);
DISPLAY 1.595745 (-5600 3300);
PAINT GREEN (-5600 3300);
DISPLAY INVISIBLE (-5600 3300);
FORCEPROP 2 LAST CDS_LIB mstr_standard
J 0
(-5600 3350);
PAINT MONO (-5600 3350);
DISPLAY INVISIBLE (-5600 3350);
FORCEADD TAP..6
(-5600 650);
FORCEPROP 3 LASTPIN (-5550 650) SIG_NAME M_M_CLK_DN<1>
J 0
(-5540 660);
DISPLAY 0.659574 (-5540 660);
PAINT MONO (-5540 660);
DISPLAY INVISIBLE (-5540 660);
FORCEPROP 1 LASTPIN (-5550 650) BN 1
J 0
(-5602 658);
DISPLAY 0.617021 (-5602 658);
PAINT GREEN (-5602 658);
FORCEPROP 1 LAST PATH I6
J 0
(-5602 650);
DISPLAY 0.872340 (-5602 650);
PAINT GREEN (-5602 650);
DISPLAY INVISIBLE (-5602 650);
FORCEPROP 1 LAST HDL_TAP TRUE
J 0
(-5275 525);
DISPLAY 1.595745 (-5275 525);
PAINT GREEN (-5275 525);
DISPLAY INVISIBLE (-5275 525);
FORCEPROP 1 LAST BODY_TYPE PLUMBING
J 0
(-5600 600);
DISPLAY 1.595745 (-5600 600);
PAINT GREEN (-5600 600);
DISPLAY INVISIBLE (-5600 600);
FORCEPROP 2 LAST CDS_LIB mstr_standard
J 0
(-5600 650);
PAINT MONO (-5600 650);
DISPLAY INVISIBLE (-5600 650);
FORCEADD TAP..6
(-5600 3400);
FORCEPROP 3 LASTPIN (-5550 3400) SIG_NAME M_M_DQ<38>
J 0
(-5540 3410);
DISPLAY 0.659574 (-5540 3410);
PAINT MONO (-5540 3410);
DISPLAY INVISIBLE (-5540 3410);
FORCEPROP 1 LASTPIN (-5550 3400) BN 38
J 0
(-5602 3408);
DISPLAY 0.617021 (-5602 3408);
PAINT GREEN (-5602 3408);
FORCEPROP 1 LAST PATH I60
J 0
(-5602 3400);
DISPLAY 0.872340 (-5602 3400);
PAINT GREEN (-5602 3400);
DISPLAY INVISIBLE (-5602 3400);
FORCEPROP 1 LAST HDL_TAP TRUE
J 0
(-5275 3275);
DISPLAY 1.595745 (-5275 3275);
PAINT GREEN (-5275 3275);
DISPLAY INVISIBLE (-5275 3275);
FORCEPROP 1 LAST BODY_TYPE PLUMBING
J 0
(-5600 3350);
DISPLAY 1.595745 (-5600 3350);
PAINT GREEN (-5600 3350);
DISPLAY INVISIBLE (-5600 3350);
FORCEPROP 2 LAST CDS_LIB mstr_standard
J 0
(-5600 3400);
PAINT MONO (-5600 3400);
DISPLAY INVISIBLE (-5600 3400);
FORCEADD TAP..6
(-5600 3450);
FORCEPROP 3 LASTPIN (-5550 3450) SIG_NAME M_M_DQ<39>
J 0
(-5540 3460);
DISPLAY 0.659574 (-5540 3460);
PAINT MONO (-5540 3460);
DISPLAY INVISIBLE (-5540 3460);
FORCEPROP 1 LASTPIN (-5550 3450) BN 39
J 0
(-5602 3458);
DISPLAY 0.617021 (-5602 3458);
PAINT GREEN (-5602 3458);
FORCEPROP 1 LAST PATH I61
J 0
(-5602 3450);
DISPLAY 0.872340 (-5602 3450);
PAINT GREEN (-5602 3450);
DISPLAY INVISIBLE (-5602 3450);
FORCEPROP 1 LAST HDL_TAP TRUE
J 0
(-5275 3325);
DISPLAY 1.595745 (-5275 3325);
PAINT GREEN (-5275 3325);
DISPLAY INVISIBLE (-5275 3325);
FORCEPROP 1 LAST BODY_TYPE PLUMBING
J 0
(-5600 3400);
DISPLAY 1.595745 (-5600 3400);
PAINT GREEN (-5600 3400);
DISPLAY INVISIBLE (-5600 3400);
FORCEPROP 2 LAST CDS_LIB mstr_standard
J 0
(-5600 3450);
PAINT MONO (-5600 3450);
DISPLAY INVISIBLE (-5600 3450);
FORCEADD TAP..6
(-5600 3500);
FORCEPROP 3 LASTPIN (-5550 3500) SIG_NAME M_M_DQ<40>
J 0
(-5540 3510);
DISPLAY 0.659574 (-5540 3510);
PAINT MONO (-5540 3510);
DISPLAY INVISIBLE (-5540 3510);
FORCEPROP 1 LASTPIN (-5550 3500) BN 40
J 0
(-5602 3508);
DISPLAY 0.617021 (-5602 3508);
PAINT GREEN (-5602 3508);
FORCEPROP 1 LAST PATH I62
J 0
(-5602 3500);
DISPLAY 0.872340 (-5602 3500);
PAINT GREEN (-5602 3500);
DISPLAY INVISIBLE (-5602 3500);
FORCEPROP 1 LAST HDL_TAP TRUE
J 0
(-5275 3375);
DISPLAY 1.595745 (-5275 3375);
PAINT GREEN (-5275 3375);
DISPLAY INVISIBLE (-5275 3375);
FORCEPROP 1 LAST BODY_TYPE PLUMBING
J 0
(-5600 3450);
DISPLAY 1.595745 (-5600 3450);
PAINT GREEN (-5600 3450);
DISPLAY INVISIBLE (-5600 3450);
FORCEPROP 2 LAST CDS_LIB mstr_standard
J 0
(-5600 3500);
PAINT MONO (-5600 3500);
DISPLAY INVISIBLE (-5600 3500);
FORCEADD TAP..6
(-5600 3550);
FORCEPROP 3 LASTPIN (-5550 3550) SIG_NAME M_M_DQ<41>
J 0
(-5540 3560);
DISPLAY 0.659574 (-5540 3560);
PAINT MONO (-5540 3560);
DISPLAY INVISIBLE (-5540 3560);
FORCEPROP 1 LASTPIN (-5550 3550) BN 41
J 0
(-5602 3558);
DISPLAY 0.617021 (-5602 3558);
PAINT GREEN (-5602 3558);
FORCEPROP 1 LAST PATH I63
J 0
(-5602 3550);
DISPLAY 0.872340 (-5602 3550);
PAINT GREEN (-5602 3550);
DISPLAY INVISIBLE (-5602 3550);
FORCEPROP 1 LAST HDL_TAP TRUE
J 0
(-5275 3425);
DISPLAY 1.595745 (-5275 3425);
PAINT GREEN (-5275 3425);
DISPLAY INVISIBLE (-5275 3425);
FORCEPROP 1 LAST BODY_TYPE PLUMBING
J 0
(-5600 3500);
DISPLAY 1.595745 (-5600 3500);
PAINT GREEN (-5600 3500);
DISPLAY INVISIBLE (-5600 3500);
FORCEPROP 2 LAST CDS_LIB mstr_standard
J 0
(-5600 3550);
PAINT MONO (-5600 3550);
DISPLAY INVISIBLE (-5600 3550);
FORCEADD TAP..6
(-5600 3600);
FORCEPROP 3 LASTPIN (-5550 3600) SIG_NAME M_M_DQ<42>
J 0
(-5540 3610);
DISPLAY 0.659574 (-5540 3610);
PAINT MONO (-5540 3610);
DISPLAY INVISIBLE (-5540 3610);
FORCEPROP 1 LASTPIN (-5550 3600) BN 42
J 0
(-5602 3608);
DISPLAY 0.617021 (-5602 3608);
PAINT GREEN (-5602 3608);
FORCEPROP 1 LAST PATH I64
J 0
(-5602 3600);
DISPLAY 0.872340 (-5602 3600);
PAINT GREEN (-5602 3600);
DISPLAY INVISIBLE (-5602 3600);
FORCEPROP 1 LAST HDL_TAP TRUE
J 0
(-5275 3475);
DISPLAY 1.595745 (-5275 3475);
PAINT GREEN (-5275 3475);
DISPLAY INVISIBLE (-5275 3475);
FORCEPROP 1 LAST BODY_TYPE PLUMBING
J 0
(-5600 3550);
DISPLAY 1.595745 (-5600 3550);
PAINT GREEN (-5600 3550);
DISPLAY INVISIBLE (-5600 3550);
FORCEPROP 2 LAST CDS_LIB mstr_standard
J 0
(-5600 3600);
PAINT MONO (-5600 3600);
DISPLAY INVISIBLE (-5600 3600);
FORCEADD TAP..6
(-5600 3650);
FORCEPROP 3 LASTPIN (-5550 3650) SIG_NAME M_M_DQ<43>
J 0
(-5540 3660);
DISPLAY 0.659574 (-5540 3660);
PAINT MONO (-5540 3660);
DISPLAY INVISIBLE (-5540 3660);
FORCEPROP 1 LASTPIN (-5550 3650) BN 43
J 0
(-5602 3658);
DISPLAY 0.617021 (-5602 3658);
PAINT GREEN (-5602 3658);
FORCEPROP 1 LAST PATH I65
J 0
(-5602 3650);
DISPLAY 0.872340 (-5602 3650);
PAINT GREEN (-5602 3650);
DISPLAY INVISIBLE (-5602 3650);
FORCEPROP 1 LAST HDL_TAP TRUE
J 0
(-5275 3525);
DISPLAY 1.595745 (-5275 3525);
PAINT GREEN (-5275 3525);
DISPLAY INVISIBLE (-5275 3525);
FORCEPROP 1 LAST BODY_TYPE PLUMBING
J 0
(-5600 3600);
DISPLAY 1.595745 (-5600 3600);
PAINT GREEN (-5600 3600);
DISPLAY INVISIBLE (-5600 3600);
FORCEPROP 2 LAST CDS_LIB mstr_standard
J 0
(-5600 3650);
PAINT MONO (-5600 3650);
DISPLAY INVISIBLE (-5600 3650);
FORCEADD TAP..6
(-5600 3700);
FORCEPROP 3 LASTPIN (-5550 3700) SIG_NAME M_M_DQ<44>
J 0
(-5540 3710);
DISPLAY 0.659574 (-5540 3710);
PAINT MONO (-5540 3710);
DISPLAY INVISIBLE (-5540 3710);
FORCEPROP 1 LASTPIN (-5550 3700) BN 44
J 0
(-5602 3708);
DISPLAY 0.617021 (-5602 3708);
PAINT GREEN (-5602 3708);
FORCEPROP 1 LAST PATH I66
J 0
(-5602 3700);
DISPLAY 0.872340 (-5602 3700);
PAINT GREEN (-5602 3700);
DISPLAY INVISIBLE (-5602 3700);
FORCEPROP 1 LAST HDL_TAP TRUE
J 0
(-5275 3575);
DISPLAY 1.595745 (-5275 3575);
PAINT GREEN (-5275 3575);
DISPLAY INVISIBLE (-5275 3575);
FORCEPROP 1 LAST BODY_TYPE PLUMBING
J 0
(-5600 3650);
DISPLAY 1.595745 (-5600 3650);
PAINT GREEN (-5600 3650);
DISPLAY INVISIBLE (-5600 3650);
FORCEPROP 2 LAST CDS_LIB mstr_standard
J 0
(-5600 3700);
PAINT MONO (-5600 3700);
DISPLAY INVISIBLE (-5600 3700);
FORCEADD TAP..6
(-5600 3750);
FORCEPROP 3 LASTPIN (-5550 3750) SIG_NAME M_M_DQ<45>
J 0
(-5540 3760);
DISPLAY 0.659574 (-5540 3760);
PAINT MONO (-5540 3760);
DISPLAY INVISIBLE (-5540 3760);
FORCEPROP 1 LASTPIN (-5550 3750) BN 45
J 0
(-5602 3758);
DISPLAY 0.617021 (-5602 3758);
PAINT GREEN (-5602 3758);
FORCEPROP 1 LAST PATH I67
J 0
(-5602 3750);
DISPLAY 0.872340 (-5602 3750);
PAINT GREEN (-5602 3750);
DISPLAY INVISIBLE (-5602 3750);
FORCEPROP 1 LAST HDL_TAP TRUE
J 0
(-5275 3625);
DISPLAY 1.595745 (-5275 3625);
PAINT GREEN (-5275 3625);
DISPLAY INVISIBLE (-5275 3625);
FORCEPROP 1 LAST BODY_TYPE PLUMBING
J 0
(-5600 3700);
DISPLAY 1.595745 (-5600 3700);
PAINT GREEN (-5600 3700);
DISPLAY INVISIBLE (-5600 3700);
FORCEPROP 2 LAST CDS_LIB mstr_standard
J 0
(-5600 3750);
PAINT MONO (-5600 3750);
DISPLAY INVISIBLE (-5600 3750);
FORCEADD TAP..6
(-5600 3800);
FORCEPROP 3 LASTPIN (-5550 3800) SIG_NAME M_M_DQ<46>
J 0
(-5540 3810);
DISPLAY 0.659574 (-5540 3810);
PAINT MONO (-5540 3810);
DISPLAY INVISIBLE (-5540 3810);
FORCEPROP 1 LASTPIN (-5550 3800) BN 46
J 0
(-5602 3808);
DISPLAY 0.617021 (-5602 3808);
PAINT GREEN (-5602 3808);
FORCEPROP 1 LAST PATH I68
J 0
(-5602 3800);
DISPLAY 0.872340 (-5602 3800);
PAINT GREEN (-5602 3800);
DISPLAY INVISIBLE (-5602 3800);
FORCEPROP 1 LAST HDL_TAP TRUE
J 0
(-5275 3675);
DISPLAY 1.595745 (-5275 3675);
PAINT GREEN (-5275 3675);
DISPLAY INVISIBLE (-5275 3675);
FORCEPROP 1 LAST BODY_TYPE PLUMBING
J 0
(-5600 3750);
DISPLAY 1.595745 (-5600 3750);
PAINT GREEN (-5600 3750);
DISPLAY INVISIBLE (-5600 3750);
FORCEPROP 2 LAST CDS_LIB mstr_standard
J 0
(-5600 3800);
PAINT MONO (-5600 3800);
DISPLAY INVISIBLE (-5600 3800);
FORCEADD TAP..6
(-5600 3850);
FORCEPROP 3 LASTPIN (-5550 3850) SIG_NAME M_M_DQ<47>
J 0
(-5540 3860);
DISPLAY 0.659574 (-5540 3860);
PAINT MONO (-5540 3860);
DISPLAY INVISIBLE (-5540 3860);
FORCEPROP 1 LASTPIN (-5550 3850) BN 47
J 0
(-5602 3858);
DISPLAY 0.617021 (-5602 3858);
PAINT GREEN (-5602 3858);
FORCEPROP 1 LAST PATH I69
J 0
(-5602 3850);
DISPLAY 0.872340 (-5602 3850);
PAINT GREEN (-5602 3850);
DISPLAY INVISIBLE (-5602 3850);
FORCEPROP 1 LAST HDL_TAP TRUE
J 0
(-5275 3725);
DISPLAY 1.595745 (-5275 3725);
PAINT GREEN (-5275 3725);
DISPLAY INVISIBLE (-5275 3725);
FORCEPROP 1 LAST BODY_TYPE PLUMBING
J 0
(-5600 3800);
DISPLAY 1.595745 (-5600 3800);
PAINT GREEN (-5600 3800);
DISPLAY INVISIBLE (-5600 3800);
FORCEPROP 2 LAST CDS_LIB mstr_standard
J 0
(-5600 3850);
PAINT MONO (-5600 3850);
DISPLAY INVISIBLE (-5600 3850);
FORCEADD TAP..6
(-5600 750);
FORCEPROP 3 LASTPIN (-5550 750) SIG_NAME M_M_CLK_DN<3>
J 0
(-5540 760);
DISPLAY 0.659574 (-5540 760);
PAINT MONO (-5540 760);
DISPLAY INVISIBLE (-5540 760);
FORCEPROP 1 LASTPIN (-5550 750) BN 3
J 0
(-5602 758);
DISPLAY 0.617021 (-5602 758);
PAINT GREEN (-5602 758);
FORCEPROP 1 LAST PATH I7
J 0
(-5602 750);
DISPLAY 0.872340 (-5602 750);
PAINT GREEN (-5602 750);
DISPLAY INVISIBLE (-5602 750);
FORCEPROP 1 LAST HDL_TAP TRUE
J 0
(-5275 625);
DISPLAY 1.595745 (-5275 625);
PAINT GREEN (-5275 625);
DISPLAY INVISIBLE (-5275 625);
FORCEPROP 1 LAST BODY_TYPE PLUMBING
J 0
(-5600 700);
DISPLAY 1.595745 (-5600 700);
PAINT GREEN (-5600 700);
DISPLAY INVISIBLE (-5600 700);
FORCEPROP 2 LAST CDS_LIB mstr_standard
J 0
(-5600 750);
PAINT MONO (-5600 750);
DISPLAY INVISIBLE (-5600 750);
FORCEADD TAP..6
(-5600 3900);
FORCEPROP 3 LASTPIN (-5550 3900) SIG_NAME M_M_DQ<48>
J 0
(-5540 3910);
DISPLAY 0.659574 (-5540 3910);
PAINT MONO (-5540 3910);
DISPLAY INVISIBLE (-5540 3910);
FORCEPROP 1 LASTPIN (-5550 3900) BN 48
J 0
(-5602 3908);
DISPLAY 0.617021 (-5602 3908);
PAINT GREEN (-5602 3908);
FORCEPROP 1 LAST PATH I70
J 0
(-5602 3900);
DISPLAY 0.872340 (-5602 3900);
PAINT GREEN (-5602 3900);
DISPLAY INVISIBLE (-5602 3900);
FORCEPROP 1 LAST HDL_TAP TRUE
J 0
(-5275 3775);
DISPLAY 1.595745 (-5275 3775);
PAINT GREEN (-5275 3775);
DISPLAY INVISIBLE (-5275 3775);
FORCEPROP 1 LAST BODY_TYPE PLUMBING
J 0
(-5600 3850);
DISPLAY 1.595745 (-5600 3850);
PAINT GREEN (-5600 3850);
DISPLAY INVISIBLE (-5600 3850);
FORCEPROP 2 LAST CDS_LIB mstr_standard
J 0
(-5600 3900);
PAINT MONO (-5600 3900);
DISPLAY INVISIBLE (-5600 3900);
FORCEADD TAP..6
(-5600 3950);
FORCEPROP 3 LASTPIN (-5550 3950) SIG_NAME M_M_DQ<49>
J 0
(-5540 3960);
DISPLAY 0.659574 (-5540 3960);
PAINT MONO (-5540 3960);
DISPLAY INVISIBLE (-5540 3960);
FORCEPROP 1 LASTPIN (-5550 3950) BN 49
J 0
(-5602 3958);
DISPLAY 0.617021 (-5602 3958);
PAINT GREEN (-5602 3958);
FORCEPROP 1 LAST PATH I71
J 0
(-5602 3950);
DISPLAY 0.872340 (-5602 3950);
PAINT GREEN (-5602 3950);
DISPLAY INVISIBLE (-5602 3950);
FORCEPROP 1 LAST HDL_TAP TRUE
J 0
(-5275 3825);
DISPLAY 1.595745 (-5275 3825);
PAINT GREEN (-5275 3825);
DISPLAY INVISIBLE (-5275 3825);
FORCEPROP 1 LAST BODY_TYPE PLUMBING
J 0
(-5600 3900);
DISPLAY 1.595745 (-5600 3900);
PAINT GREEN (-5600 3900);
DISPLAY INVISIBLE (-5600 3900);
FORCEPROP 2 LAST CDS_LIB mstr_standard
J 0
(-5600 3950);
PAINT MONO (-5600 3950);
DISPLAY INVISIBLE (-5600 3950);
FORCEADD OFFPAGE..6
(-6450 4775);
FORCEPROP 2 LAST $XR1 88 
J 0
(-6789 4775);
DISPLAY 0.638298 (-6789 4775);
PAINT MONO (-6789 4775);
FORCEPROP 2 LAST $XR0 87 
J 0
(-6699 4775);
DISPLAY 0.638298 (-6699 4775);
PAINT MONO (-6699 4775);
FORCEPROP 2 LAST PATH I72
J 0
(-6400 4850);
DISPLAY 1.021277 (-6400 4850);
PAINT ORANGE (-6400 4850);
DISPLAY INVISIBLE (-6400 4850);
FORCEPROP 1 LAST COMMENT_BODY TRUE
J 0
(-6350 4700);
DISPLAY 1.170213 (-6350 4700);
PAINT GREEN (-6350 4700);
DISPLAY INVISIBLE (-6350 4700);
FORCEPROP 1 LAST OFFPAGE TRUE
J 0
(-6125 4650);
DISPLAY 1.170213 (-6125 4650);
PAINT GREEN (-6125 4650);
DISPLAY INVISIBLE (-6125 4650);
FORCEPROP 2 LAST CDS_LIB mstr_standard
J 0
(-6450 4775);
PAINT MONO (-6450 4775);
DISPLAY INVISIBLE (-6450 4775);
FORCEADD TAP..6
(-5600 4000);
FORCEPROP 3 LASTPIN (-5550 4000) SIG_NAME M_M_DQ<50>
J 0
(-5540 4010);
DISPLAY 0.659574 (-5540 4010);
PAINT MONO (-5540 4010);
DISPLAY INVISIBLE (-5540 4010);
FORCEPROP 1 LASTPIN (-5550 4000) BN 50
J 0
(-5602 4008);
DISPLAY 0.617021 (-5602 4008);
PAINT GREEN (-5602 4008);
FORCEPROP 1 LAST PATH I73
J 0
(-5602 4000);
DISPLAY 0.872340 (-5602 4000);
PAINT GREEN (-5602 4000);
DISPLAY INVISIBLE (-5602 4000);
FORCEPROP 1 LAST HDL_TAP TRUE
J 0
(-5275 3875);
DISPLAY 1.595745 (-5275 3875);
PAINT GREEN (-5275 3875);
DISPLAY INVISIBLE (-5275 3875);
FORCEPROP 1 LAST BODY_TYPE PLUMBING
J 0
(-5600 3950);
DISPLAY 1.595745 (-5600 3950);
PAINT GREEN (-5600 3950);
DISPLAY INVISIBLE (-5600 3950);
FORCEPROP 2 LAST CDS_LIB mstr_standard
J 0
(-5600 4000);
PAINT MONO (-5600 4000);
DISPLAY INVISIBLE (-5600 4000);
FORCEADD TAP..6
(-5600 4050);
FORCEPROP 3 LASTPIN (-5550 4050) SIG_NAME M_M_DQ<51>
J 0
(-5540 4060);
DISPLAY 0.659574 (-5540 4060);
PAINT MONO (-5540 4060);
DISPLAY INVISIBLE (-5540 4060);
FORCEPROP 1 LASTPIN (-5550 4050) BN 51
J 0
(-5602 4058);
DISPLAY 0.617021 (-5602 4058);
PAINT GREEN (-5602 4058);
FORCEPROP 1 LAST PATH I74
J 0
(-5602 4050);
DISPLAY 0.872340 (-5602 4050);
PAINT GREEN (-5602 4050);
DISPLAY INVISIBLE (-5602 4050);
FORCEPROP 1 LAST HDL_TAP TRUE
J 0
(-5275 3925);
DISPLAY 1.595745 (-5275 3925);
PAINT GREEN (-5275 3925);
DISPLAY INVISIBLE (-5275 3925);
FORCEPROP 1 LAST BODY_TYPE PLUMBING
J 0
(-5600 4000);
DISPLAY 1.595745 (-5600 4000);
PAINT GREEN (-5600 4000);
DISPLAY INVISIBLE (-5600 4000);
FORCEPROP 2 LAST CDS_LIB mstr_standard
J 0
(-5600 4050);
PAINT MONO (-5600 4050);
DISPLAY INVISIBLE (-5600 4050);
FORCEADD TAP..6
(-5600 4100);
FORCEPROP 3 LASTPIN (-5550 4100) SIG_NAME M_M_DQ<52>
J 0
(-5540 4110);
DISPLAY 0.659574 (-5540 4110);
PAINT MONO (-5540 4110);
DISPLAY INVISIBLE (-5540 4110);
FORCEPROP 1 LASTPIN (-5550 4100) BN 52
J 0
(-5602 4108);
DISPLAY 0.617021 (-5602 4108);
PAINT GREEN (-5602 4108);
FORCEPROP 1 LAST PATH I75
J 0
(-5602 4100);
DISPLAY 0.872340 (-5602 4100);
PAINT GREEN (-5602 4100);
DISPLAY INVISIBLE (-5602 4100);
FORCEPROP 1 LAST HDL_TAP TRUE
J 0
(-5275 3975);
DISPLAY 1.595745 (-5275 3975);
PAINT GREEN (-5275 3975);
DISPLAY INVISIBLE (-5275 3975);
FORCEPROP 1 LAST BODY_TYPE PLUMBING
J 0
(-5600 4050);
DISPLAY 1.595745 (-5600 4050);
PAINT GREEN (-5600 4050);
DISPLAY INVISIBLE (-5600 4050);
FORCEPROP 2 LAST CDS_LIB mstr_standard
J 0
(-5600 4100);
PAINT MONO (-5600 4100);
DISPLAY INVISIBLE (-5600 4100);
FORCEADD TAP..6
(-5600 4150);
FORCEPROP 3 LASTPIN (-5550 4150) SIG_NAME M_M_DQ<53>
J 0
(-5540 4160);
DISPLAY 0.659574 (-5540 4160);
PAINT MONO (-5540 4160);
DISPLAY INVISIBLE (-5540 4160);
FORCEPROP 1 LASTPIN (-5550 4150) BN 53
J 0
(-5602 4158);
DISPLAY 0.617021 (-5602 4158);
PAINT GREEN (-5602 4158);
FORCEPROP 1 LAST PATH I76
J 0
(-5602 4150);
DISPLAY 0.872340 (-5602 4150);
PAINT GREEN (-5602 4150);
DISPLAY INVISIBLE (-5602 4150);
FORCEPROP 1 LAST HDL_TAP TRUE
J 0
(-5275 4025);
DISPLAY 1.595745 (-5275 4025);
PAINT GREEN (-5275 4025);
DISPLAY INVISIBLE (-5275 4025);
FORCEPROP 1 LAST BODY_TYPE PLUMBING
J 0
(-5600 4100);
DISPLAY 1.595745 (-5600 4100);
PAINT GREEN (-5600 4100);
DISPLAY INVISIBLE (-5600 4100);
FORCEPROP 2 LAST CDS_LIB mstr_standard
J 0
(-5600 4150);
PAINT MONO (-5600 4150);
DISPLAY INVISIBLE (-5600 4150);
FORCEADD TAP..6
(-5600 4200);
FORCEPROP 3 LASTPIN (-5550 4200) SIG_NAME M_M_DQ<54>
J 0
(-5540 4210);
DISPLAY 0.659574 (-5540 4210);
PAINT MONO (-5540 4210);
DISPLAY INVISIBLE (-5540 4210);
FORCEPROP 1 LASTPIN (-5550 4200) BN 54
J 0
(-5602 4208);
DISPLAY 0.617021 (-5602 4208);
PAINT GREEN (-5602 4208);
FORCEPROP 1 LAST PATH I77
J 0
(-5602 4200);
DISPLAY 0.872340 (-5602 4200);
PAINT GREEN (-5602 4200);
DISPLAY INVISIBLE (-5602 4200);
FORCEPROP 1 LAST HDL_TAP TRUE
J 0
(-5275 4075);
DISPLAY 1.595745 (-5275 4075);
PAINT GREEN (-5275 4075);
DISPLAY INVISIBLE (-5275 4075);
FORCEPROP 1 LAST BODY_TYPE PLUMBING
J 0
(-5600 4150);
DISPLAY 1.595745 (-5600 4150);
PAINT GREEN (-5600 4150);
DISPLAY INVISIBLE (-5600 4150);
FORCEPROP 2 LAST CDS_LIB mstr_standard
J 0
(-5600 4200);
PAINT MONO (-5600 4200);
DISPLAY INVISIBLE (-5600 4200);
FORCEADD TAP..6
(-5600 4250);
FORCEPROP 3 LASTPIN (-5550 4250) SIG_NAME M_M_DQ<55>
J 0
(-5540 4260);
DISPLAY 0.659574 (-5540 4260);
PAINT MONO (-5540 4260);
DISPLAY INVISIBLE (-5540 4260);
FORCEPROP 1 LASTPIN (-5550 4250) BN 55
J 0
(-5602 4258);
DISPLAY 0.617021 (-5602 4258);
PAINT GREEN (-5602 4258);
FORCEPROP 1 LAST PATH I78
J 0
(-5602 4250);
DISPLAY 0.872340 (-5602 4250);
PAINT GREEN (-5602 4250);
DISPLAY INVISIBLE (-5602 4250);
FORCEPROP 1 LAST HDL_TAP TRUE
J 0
(-5275 4125);
DISPLAY 1.595745 (-5275 4125);
PAINT GREEN (-5275 4125);
DISPLAY INVISIBLE (-5275 4125);
FORCEPROP 1 LAST BODY_TYPE PLUMBING
J 0
(-5600 4200);
DISPLAY 1.595745 (-5600 4200);
PAINT GREEN (-5600 4200);
DISPLAY INVISIBLE (-5600 4200);
FORCEPROP 2 LAST CDS_LIB mstr_standard
J 0
(-5600 4250);
PAINT MONO (-5600 4250);
DISPLAY INVISIBLE (-5600 4250);
FORCEADD TAP..6
(-5600 4300);
FORCEPROP 3 LASTPIN (-5550 4300) SIG_NAME M_M_DQ<56>
J 0
(-5540 4310);
DISPLAY 0.659574 (-5540 4310);
PAINT MONO (-5540 4310);
DISPLAY INVISIBLE (-5540 4310);
FORCEPROP 1 LASTPIN (-5550 4300) BN 56
J 0
(-5602 4308);
DISPLAY 0.617021 (-5602 4308);
PAINT GREEN (-5602 4308);
FORCEPROP 1 LAST PATH I79
J 0
(-5602 4300);
DISPLAY 0.872340 (-5602 4300);
PAINT GREEN (-5602 4300);
DISPLAY INVISIBLE (-5602 4300);
FORCEPROP 1 LAST HDL_TAP TRUE
J 0
(-5275 4175);
DISPLAY 1.595745 (-5275 4175);
PAINT GREEN (-5275 4175);
DISPLAY INVISIBLE (-5275 4175);
FORCEPROP 1 LAST BODY_TYPE PLUMBING
J 0
(-5600 4250);
DISPLAY 1.595745 (-5600 4250);
PAINT GREEN (-5600 4250);
DISPLAY INVISIBLE (-5600 4250);
FORCEPROP 2 LAST CDS_LIB mstr_standard
J 0
(-5600 4300);
PAINT MONO (-5600 4300);
DISPLAY INVISIBLE (-5600 4300);
FORCEADD TAP..6
(-5600 700);
FORCEPROP 3 LASTPIN (-5550 700) SIG_NAME M_M_CLK_DN<2>
J 0
(-5540 710);
DISPLAY 0.659574 (-5540 710);
PAINT MONO (-5540 710);
DISPLAY INVISIBLE (-5540 710);
FORCEPROP 1 LASTPIN (-5550 700) BN 2
J 0
(-5602 708);
DISPLAY 0.617021 (-5602 708);
PAINT GREEN (-5602 708);
FORCEPROP 1 LAST PATH I8
J 0
(-5602 700);
DISPLAY 0.872340 (-5602 700);
PAINT GREEN (-5602 700);
DISPLAY INVISIBLE (-5602 700);
FORCEPROP 1 LAST HDL_TAP TRUE
J 0
(-5275 575);
DISPLAY 1.595745 (-5275 575);
PAINT GREEN (-5275 575);
DISPLAY INVISIBLE (-5275 575);
FORCEPROP 1 LAST BODY_TYPE PLUMBING
J 0
(-5600 650);
DISPLAY 1.595745 (-5600 650);
PAINT GREEN (-5600 650);
DISPLAY INVISIBLE (-5600 650);
FORCEPROP 2 LAST CDS_LIB mstr_standard
J 0
(-5600 700);
PAINT MONO (-5600 700);
DISPLAY INVISIBLE (-5600 700);
FORCEADD TAP..6
(-5600 4350);
FORCEPROP 3 LASTPIN (-5550 4350) SIG_NAME M_M_DQ<57>
J 0
(-5540 4360);
DISPLAY 0.659574 (-5540 4360);
PAINT MONO (-5540 4360);
DISPLAY INVISIBLE (-5540 4360);
FORCEPROP 1 LASTPIN (-5550 4350) BN 57
J 0
(-5602 4358);
DISPLAY 0.617021 (-5602 4358);
PAINT GREEN (-5602 4358);
FORCEPROP 1 LAST PATH I80
J 0
(-5602 4350);
DISPLAY 0.872340 (-5602 4350);
PAINT GREEN (-5602 4350);
DISPLAY INVISIBLE (-5602 4350);
FORCEPROP 1 LAST HDL_TAP TRUE
J 0
(-5275 4225);
DISPLAY 1.595745 (-5275 4225);
PAINT GREEN (-5275 4225);
DISPLAY INVISIBLE (-5275 4225);
FORCEPROP 1 LAST BODY_TYPE PLUMBING
J 0
(-5600 4300);
DISPLAY 1.595745 (-5600 4300);
PAINT GREEN (-5600 4300);
DISPLAY INVISIBLE (-5600 4300);
FORCEPROP 2 LAST CDS_LIB mstr_standard
J 0
(-5600 4350);
PAINT MONO (-5600 4350);
DISPLAY INVISIBLE (-5600 4350);
FORCEADD TAP..6
(-5600 4400);
FORCEPROP 3 LASTPIN (-5550 4400) SIG_NAME M_M_DQ<58>
J 0
(-5540 4410);
DISPLAY 0.659574 (-5540 4410);
PAINT MONO (-5540 4410);
DISPLAY INVISIBLE (-5540 4410);
FORCEPROP 1 LASTPIN (-5550 4400) BN 58
J 0
(-5602 4408);
DISPLAY 0.617021 (-5602 4408);
PAINT GREEN (-5602 4408);
FORCEPROP 1 LAST PATH I81
J 0
(-5602 4400);
DISPLAY 0.872340 (-5602 4400);
PAINT GREEN (-5602 4400);
DISPLAY INVISIBLE (-5602 4400);
FORCEPROP 1 LAST HDL_TAP TRUE
J 0
(-5275 4275);
DISPLAY 1.595745 (-5275 4275);
PAINT GREEN (-5275 4275);
DISPLAY INVISIBLE (-5275 4275);
FORCEPROP 1 LAST BODY_TYPE PLUMBING
J 0
(-5600 4350);
DISPLAY 1.595745 (-5600 4350);
PAINT GREEN (-5600 4350);
DISPLAY INVISIBLE (-5600 4350);
FORCEPROP 2 LAST CDS_LIB mstr_standard
J 0
(-5600 4400);
PAINT MONO (-5600 4400);
DISPLAY INVISIBLE (-5600 4400);
FORCEADD TAP..6
(-5600 4450);
FORCEPROP 3 LASTPIN (-5550 4450) SIG_NAME M_M_DQ<59>
J 0
(-5540 4460);
DISPLAY 0.659574 (-5540 4460);
PAINT MONO (-5540 4460);
DISPLAY INVISIBLE (-5540 4460);
FORCEPROP 1 LASTPIN (-5550 4450) BN 59
J 0
(-5602 4458);
DISPLAY 0.617021 (-5602 4458);
PAINT GREEN (-5602 4458);
FORCEPROP 1 LAST PATH I82
J 0
(-5602 4450);
DISPLAY 0.872340 (-5602 4450);
PAINT GREEN (-5602 4450);
DISPLAY INVISIBLE (-5602 4450);
FORCEPROP 1 LAST HDL_TAP TRUE
J 0
(-5275 4325);
DISPLAY 1.595745 (-5275 4325);
PAINT GREEN (-5275 4325);
DISPLAY INVISIBLE (-5275 4325);
FORCEPROP 1 LAST BODY_TYPE PLUMBING
J 0
(-5600 4400);
DISPLAY 1.595745 (-5600 4400);
PAINT GREEN (-5600 4400);
DISPLAY INVISIBLE (-5600 4400);
FORCEPROP 2 LAST CDS_LIB mstr_standard
J 0
(-5600 4450);
PAINT MONO (-5600 4450);
DISPLAY INVISIBLE (-5600 4450);
FORCEADD TAP..6
(-5600 4500);
FORCEPROP 3 LASTPIN (-5550 4500) SIG_NAME M_M_DQ<60>
J 0
(-5540 4510);
DISPLAY 0.659574 (-5540 4510);
PAINT MONO (-5540 4510);
DISPLAY INVISIBLE (-5540 4510);
FORCEPROP 1 LASTPIN (-5550 4500) BN 60
J 0
(-5602 4508);
DISPLAY 0.617021 (-5602 4508);
PAINT GREEN (-5602 4508);
FORCEPROP 1 LAST PATH I83
J 0
(-5602 4500);
DISPLAY 0.872340 (-5602 4500);
PAINT GREEN (-5602 4500);
DISPLAY INVISIBLE (-5602 4500);
FORCEPROP 1 LAST HDL_TAP TRUE
J 0
(-5275 4375);
DISPLAY 1.595745 (-5275 4375);
PAINT GREEN (-5275 4375);
DISPLAY INVISIBLE (-5275 4375);
FORCEPROP 1 LAST BODY_TYPE PLUMBING
J 0
(-5600 4450);
DISPLAY 1.595745 (-5600 4450);
PAINT GREEN (-5600 4450);
DISPLAY INVISIBLE (-5600 4450);
FORCEPROP 2 LAST CDS_LIB mstr_standard
J 0
(-5600 4500);
PAINT MONO (-5600 4500);
DISPLAY INVISIBLE (-5600 4500);
FORCEADD TAP..6
(-5600 4550);
FORCEPROP 3 LASTPIN (-5550 4550) SIG_NAME M_M_DQ<61>
J 0
(-5540 4560);
DISPLAY 0.659574 (-5540 4560);
PAINT MONO (-5540 4560);
DISPLAY INVISIBLE (-5540 4560);
FORCEPROP 1 LASTPIN (-5550 4550) BN 61
J 0
(-5602 4558);
DISPLAY 0.617021 (-5602 4558);
PAINT GREEN (-5602 4558);
FORCEPROP 1 LAST PATH I84
J 0
(-5602 4550);
DISPLAY 0.872340 (-5602 4550);
PAINT GREEN (-5602 4550);
DISPLAY INVISIBLE (-5602 4550);
FORCEPROP 1 LAST HDL_TAP TRUE
J 0
(-5275 4425);
DISPLAY 1.595745 (-5275 4425);
PAINT GREEN (-5275 4425);
DISPLAY INVISIBLE (-5275 4425);
FORCEPROP 1 LAST BODY_TYPE PLUMBING
J 0
(-5600 4500);
DISPLAY 1.595745 (-5600 4500);
PAINT GREEN (-5600 4500);
DISPLAY INVISIBLE (-5600 4500);
FORCEPROP 2 LAST CDS_LIB mstr_standard
J 0
(-5600 4550);
PAINT MONO (-5600 4550);
DISPLAY INVISIBLE (-5600 4550);
FORCEADD TAP..6
(-5600 4600);
FORCEPROP 3 LASTPIN (-5550 4600) SIG_NAME M_M_DQ<62>
J 0
(-5540 4610);
DISPLAY 0.659574 (-5540 4610);
PAINT MONO (-5540 4610);
DISPLAY INVISIBLE (-5540 4610);
FORCEPROP 1 LASTPIN (-5550 4600) BN 62
J 0
(-5602 4608);
DISPLAY 0.617021 (-5602 4608);
PAINT GREEN (-5602 4608);
FORCEPROP 1 LAST PATH I85
J 0
(-5602 4600);
DISPLAY 0.872340 (-5602 4600);
PAINT GREEN (-5602 4600);
DISPLAY INVISIBLE (-5602 4600);
FORCEPROP 1 LAST HDL_TAP TRUE
J 0
(-5275 4475);
DISPLAY 1.595745 (-5275 4475);
PAINT GREEN (-5275 4475);
DISPLAY INVISIBLE (-5275 4475);
FORCEPROP 1 LAST BODY_TYPE PLUMBING
J 0
(-5600 4550);
DISPLAY 1.595745 (-5600 4550);
PAINT GREEN (-5600 4550);
DISPLAY INVISIBLE (-5600 4550);
FORCEPROP 2 LAST CDS_LIB mstr_standard
J 0
(-5600 4600);
PAINT MONO (-5600 4600);
DISPLAY INVISIBLE (-5600 4600);
FORCEADD TAP..6
(-5600 4650);
FORCEPROP 3 LASTPIN (-5550 4650) SIG_NAME M_M_DQ<63>
J 0
(-5540 4660);
DISPLAY 0.659574 (-5540 4660);
PAINT MONO (-5540 4660);
DISPLAY INVISIBLE (-5540 4660);
FORCEPROP 1 LASTPIN (-5550 4650) BN 63
J 0
(-5602 4658);
DISPLAY 0.617021 (-5602 4658);
PAINT GREEN (-5602 4658);
FORCEPROP 1 LAST PATH I86
J 0
(-5602 4650);
DISPLAY 0.872340 (-5602 4650);
PAINT GREEN (-5602 4650);
DISPLAY INVISIBLE (-5602 4650);
FORCEPROP 1 LAST HDL_TAP TRUE
J 0
(-5275 4525);
DISPLAY 1.595745 (-5275 4525);
PAINT GREEN (-5275 4525);
DISPLAY INVISIBLE (-5275 4525);
FORCEPROP 1 LAST BODY_TYPE PLUMBING
J 0
(-5600 4600);
DISPLAY 1.595745 (-5600 4600);
PAINT GREEN (-5600 4600);
DISPLAY INVISIBLE (-5600 4600);
FORCEPROP 2 LAST CDS_LIB mstr_standard
J 0
(-5600 4650);
PAINT MONO (-5600 4650);
DISPLAY INVISIBLE (-5600 4650);
FORCEADD TAP..6
R 2
(-2875 750);
FORCEPROP 3 LASTPIN (-2925 750) SIG_NAME M_M_BA<1>
J 0
(-2915 760);
DISPLAY 0.659574 (-2915 760);
PAINT MONO (-2915 760);
DISPLAY INVISIBLE (-2915 760);
FORCEPROP 1 LASTPIN (-2925 750) BN 1
J 2
(-2873 758);
DISPLAY 0.617021 (-2873 758);
PAINT GREEN (-2873 758);
FORCEPROP 1 LAST PATH I87
J 2
(-2873 750);
DISPLAY 0.872340 (-2873 750);
PAINT GREEN (-2873 750);
DISPLAY INVISIBLE (-2873 750);
FORCEPROP 1 LAST HDL_TAP TRUE
J 2
(-3200 625);
DISPLAY 1.595745 (-3200 625);
PAINT GREEN (-3200 625);
DISPLAY INVISIBLE (-3200 625);
FORCEPROP 1 LAST BODY_TYPE PLUMBING
J 2
(-2875 700);
DISPLAY 1.595745 (-2875 700);
PAINT GREEN (-2875 700);
DISPLAY INVISIBLE (-2875 700);
FORCEPROP 2 LAST CDS_LIB mstr_standard
J 0
(-2875 750);
PAINT MONO (-2875 750);
DISPLAY INVISIBLE (-2875 750);
FORCEADD TAP..6
R 2
(-2875 700);
FORCEPROP 3 LASTPIN (-2925 700) SIG_NAME M_M_BA<0>
J 0
(-2915 710);
DISPLAY 0.659574 (-2915 710);
PAINT MONO (-2915 710);
DISPLAY INVISIBLE (-2915 710);
FORCEPROP 1 LASTPIN (-2925 700) BN 0
J 2
(-2873 708);
DISPLAY 0.617021 (-2873 708);
PAINT GREEN (-2873 708);
FORCEPROP 1 LAST PATH I88
J 2
(-2873 700);
DISPLAY 0.872340 (-2873 700);
PAINT GREEN (-2873 700);
DISPLAY INVISIBLE (-2873 700);
FORCEPROP 1 LAST HDL_TAP TRUE
J 2
(-3200 575);
DISPLAY 1.595745 (-3200 575);
PAINT GREEN (-3200 575);
DISPLAY INVISIBLE (-3200 575);
FORCEPROP 1 LAST BODY_TYPE PLUMBING
J 2
(-2875 650);
DISPLAY 1.595745 (-2875 650);
PAINT GREEN (-2875 650);
DISPLAY INVISIBLE (-2875 650);
FORCEPROP 2 LAST CDS_LIB mstr_standard
J 0
(-2875 700);
PAINT MONO (-2875 700);
DISPLAY INVISIBLE (-2875 700);
FORCEADD TAP..6
R 2
(-2875 800);
FORCEPROP 3 LASTPIN (-2925 800) SIG_NAME M_M_BG<0>
J 0
(-2915 810);
DISPLAY 0.659574 (-2915 810);
PAINT MONO (-2915 810);
DISPLAY INVISIBLE (-2915 810);
FORCEPROP 1 LASTPIN (-2925 800) BN 0
J 2
(-2873 808);
DISPLAY 0.617021 (-2873 808);
PAINT GREEN (-2873 808);
FORCEPROP 1 LAST PATH I89
J 2
(-2873 800);
DISPLAY 0.872340 (-2873 800);
PAINT GREEN (-2873 800);
DISPLAY INVISIBLE (-2873 800);
FORCEPROP 1 LAST HDL_TAP TRUE
J 2
(-3200 675);
DISPLAY 1.595745 (-3200 675);
PAINT GREEN (-3200 675);
DISPLAY INVISIBLE (-3200 675);
FORCEPROP 1 LAST BODY_TYPE PLUMBING
J 2
(-2875 750);
DISPLAY 1.595745 (-2875 750);
PAINT GREEN (-2875 750);
DISPLAY INVISIBLE (-2875 750);
FORCEPROP 2 LAST CDS_LIB mstr_standard
J 0
(-2875 800);
PAINT MONO (-2875 800);
DISPLAY INVISIBLE (-2875 800);
FORCEADD TAP..6
(-5600 850);
FORCEPROP 3 LASTPIN (-5550 850) SIG_NAME M_M_CLK_DP<1>
J 0
(-5540 860);
DISPLAY 0.659574 (-5540 860);
PAINT MONO (-5540 860);
DISPLAY INVISIBLE (-5540 860);
FORCEPROP 1 LASTPIN (-5550 850) BN 1
J 0
(-5602 858);
DISPLAY 0.617021 (-5602 858);
PAINT GREEN (-5602 858);
FORCEPROP 1 LAST PATH I9
J 0
(-5602 850);
DISPLAY 0.872340 (-5602 850);
PAINT GREEN (-5602 850);
DISPLAY INVISIBLE (-5602 850);
FORCEPROP 1 LAST HDL_TAP TRUE
J 0
(-5275 725);
DISPLAY 1.595745 (-5275 725);
PAINT GREEN (-5275 725);
DISPLAY INVISIBLE (-5275 725);
FORCEPROP 1 LAST BODY_TYPE PLUMBING
J 0
(-5600 800);
DISPLAY 1.595745 (-5600 800);
PAINT GREEN (-5600 800);
DISPLAY INVISIBLE (-5600 800);
FORCEPROP 2 LAST CDS_LIB mstr_standard
J 0
(-5600 850);
PAINT MONO (-5600 850);
DISPLAY INVISIBLE (-5600 850);
FORCEADD TAP..6
R 2
(-2875 850);
FORCEPROP 3 LASTPIN (-2925 850) SIG_NAME M_M_BG<1>
J 0
(-2915 860);
DISPLAY 0.659574 (-2915 860);
PAINT MONO (-2915 860);
DISPLAY INVISIBLE (-2915 860);
FORCEPROP 1 LASTPIN (-2925 850) BN 1
J 2
(-2873 858);
DISPLAY 0.617021 (-2873 858);
PAINT GREEN (-2873 858);
FORCEPROP 1 LAST PATH I90
J 2
(-2873 850);
DISPLAY 0.872340 (-2873 850);
PAINT GREEN (-2873 850);
DISPLAY INVISIBLE (-2873 850);
FORCEPROP 1 LAST HDL_TAP TRUE
J 2
(-3200 725);
DISPLAY 1.595745 (-3200 725);
PAINT GREEN (-3200 725);
DISPLAY INVISIBLE (-3200 725);
FORCEPROP 1 LAST BODY_TYPE PLUMBING
J 2
(-2875 800);
DISPLAY 1.595745 (-2875 800);
PAINT GREEN (-2875 800);
DISPLAY INVISIBLE (-2875 800);
FORCEPROP 2 LAST CDS_LIB mstr_standard
J 0
(-2875 850);
PAINT MONO (-2875 850);
DISPLAY INVISIBLE (-2875 850);
FORCEADD TAP..6
R 2
(-2875 1050);
FORCEPROP 3 LASTPIN (-2925 1050) SIG_NAME M_M_CS_N<2>
J 0
(-2915 1060);
DISPLAY 0.659574 (-2915 1060);
PAINT MONO (-2915 1060);
DISPLAY INVISIBLE (-2915 1060);
FORCEPROP 1 LASTPIN (-2925 1050) BN 2
J 2
(-2873 1058);
DISPLAY 0.617021 (-2873 1058);
PAINT GREEN (-2873 1058);
FORCEPROP 1 LAST PATH I91
J 2
(-2873 1050);
DISPLAY 0.872340 (-2873 1050);
PAINT GREEN (-2873 1050);
DISPLAY INVISIBLE (-2873 1050);
FORCEPROP 1 LAST HDL_TAP TRUE
J 2
(-3200 925);
DISPLAY 1.595745 (-3200 925);
PAINT GREEN (-3200 925);
DISPLAY INVISIBLE (-3200 925);
FORCEPROP 1 LAST BODY_TYPE PLUMBING
J 2
(-2875 1000);
DISPLAY 1.595745 (-2875 1000);
PAINT GREEN (-2875 1000);
DISPLAY INVISIBLE (-2875 1000);
FORCEPROP 2 LAST CDS_LIB mstr_standard
J 0
(-2875 1050);
PAINT MONO (-2875 1050);
DISPLAY INVISIBLE (-2875 1050);
FORCEADD TAP..6
R 2
(-2875 1000);
FORCEPROP 3 LASTPIN (-2925 1000) SIG_NAME M_M_CS_N<1>
J 0
(-2915 1010);
DISPLAY 0.659574 (-2915 1010);
PAINT MONO (-2915 1010);
DISPLAY INVISIBLE (-2915 1010);
FORCEPROP 1 LASTPIN (-2925 1000) BN 1
J 2
(-2873 1008);
DISPLAY 0.617021 (-2873 1008);
PAINT GREEN (-2873 1008);
FORCEPROP 1 LAST PATH I92
J 2
(-2873 1000);
DISPLAY 0.872340 (-2873 1000);
PAINT GREEN (-2873 1000);
DISPLAY INVISIBLE (-2873 1000);
FORCEPROP 1 LAST HDL_TAP TRUE
J 2
(-3200 875);
DISPLAY 1.595745 (-3200 875);
PAINT GREEN (-3200 875);
DISPLAY INVISIBLE (-3200 875);
FORCEPROP 1 LAST BODY_TYPE PLUMBING
J 2
(-2875 950);
DISPLAY 1.595745 (-2875 950);
PAINT GREEN (-2875 950);
DISPLAY INVISIBLE (-2875 950);
FORCEPROP 2 LAST CDS_LIB mstr_standard
J 0
(-2875 1000);
PAINT MONO (-2875 1000);
DISPLAY INVISIBLE (-2875 1000);
FORCEADD TAP..6
R 2
(-2875 950);
FORCEPROP 3 LASTPIN (-2925 950) SIG_NAME M_M_CS_N<0>
J 0
(-2915 960);
DISPLAY 0.659574 (-2915 960);
PAINT MONO (-2915 960);
DISPLAY INVISIBLE (-2915 960);
FORCEPROP 1 LASTPIN (-2925 950) BN 0
J 2
(-2873 958);
DISPLAY 0.617021 (-2873 958);
PAINT GREEN (-2873 958);
FORCEPROP 1 LAST PATH I93
J 2
(-2873 950);
DISPLAY 0.872340 (-2873 950);
PAINT GREEN (-2873 950);
DISPLAY INVISIBLE (-2873 950);
FORCEPROP 1 LAST HDL_TAP TRUE
J 2
(-3200 825);
DISPLAY 1.595745 (-3200 825);
PAINT GREEN (-3200 825);
DISPLAY INVISIBLE (-3200 825);
FORCEPROP 1 LAST BODY_TYPE PLUMBING
J 2
(-2875 900);
DISPLAY 1.595745 (-2875 900);
PAINT GREEN (-2875 900);
DISPLAY INVISIBLE (-2875 900);
FORCEPROP 2 LAST CDS_LIB mstr_standard
J 0
(-2875 950);
PAINT MONO (-2875 950);
DISPLAY INVISIBLE (-2875 950);
FORCEADD TAP..6
R 2
(-2875 1150);
FORCEPROP 3 LASTPIN (-2925 1150) SIG_NAME M_M_CS_N<4>
J 0
(-2915 1160);
DISPLAY 0.659574 (-2915 1160);
PAINT MONO (-2915 1160);
DISPLAY INVISIBLE (-2915 1160);
FORCEPROP 1 LASTPIN (-2925 1150) BN 4
J 2
(-2873 1158);
DISPLAY 0.617021 (-2873 1158);
PAINT GREEN (-2873 1158);
FORCEPROP 1 LAST PATH I94
J 2
(-2873 1150);
DISPLAY 0.872340 (-2873 1150);
PAINT GREEN (-2873 1150);
DISPLAY INVISIBLE (-2873 1150);
FORCEPROP 1 LAST HDL_TAP TRUE
J 2
(-3200 1025);
DISPLAY 1.595745 (-3200 1025);
PAINT GREEN (-3200 1025);
DISPLAY INVISIBLE (-3200 1025);
FORCEPROP 1 LAST BODY_TYPE PLUMBING
J 2
(-2875 1100);
DISPLAY 1.595745 (-2875 1100);
PAINT GREEN (-2875 1100);
DISPLAY INVISIBLE (-2875 1100);
FORCEPROP 2 LAST CDS_LIB mstr_standard
J 0
(-2875 1150);
PAINT MONO (-2875 1150);
DISPLAY INVISIBLE (-2875 1150);
FORCEADD TAP..6
R 2
(-2875 1100);
FORCEPROP 3 LASTPIN (-2925 1100) SIG_NAME M_M_CS_N<3>
J 0
(-2915 1110);
DISPLAY 0.659574 (-2915 1110);
PAINT MONO (-2915 1110);
DISPLAY INVISIBLE (-2915 1110);
FORCEPROP 1 LASTPIN (-2925 1100) BN 3
J 2
(-2873 1108);
DISPLAY 0.617021 (-2873 1108);
PAINT GREEN (-2873 1108);
FORCEPROP 1 LAST PATH I95
J 2
(-2873 1100);
DISPLAY 0.872340 (-2873 1100);
PAINT GREEN (-2873 1100);
DISPLAY INVISIBLE (-2873 1100);
FORCEPROP 1 LAST HDL_TAP TRUE
J 2
(-3200 975);
DISPLAY 1.595745 (-3200 975);
PAINT GREEN (-3200 975);
DISPLAY INVISIBLE (-3200 975);
FORCEPROP 1 LAST BODY_TYPE PLUMBING
J 2
(-2875 1050);
DISPLAY 1.595745 (-2875 1050);
PAINT GREEN (-2875 1050);
DISPLAY INVISIBLE (-2875 1050);
FORCEPROP 2 LAST CDS_LIB mstr_standard
J 0
(-2875 1100);
PAINT MONO (-2875 1100);
DISPLAY INVISIBLE (-2875 1100);
FORCEADD TAP..6
R 2
(-2875 1200);
FORCEPROP 3 LASTPIN (-2925 1200) SIG_NAME M_M_CS_N<5>
J 0
(-2915 1210);
DISPLAY 0.659574 (-2915 1210);
PAINT MONO (-2915 1210);
DISPLAY INVISIBLE (-2915 1210);
FORCEPROP 1 LASTPIN (-2925 1200) BN 5
J 2
(-2873 1208);
DISPLAY 0.617021 (-2873 1208);
PAINT GREEN (-2873 1208);
FORCEPROP 1 LAST PATH I96
J 2
(-2873 1200);
DISPLAY 0.872340 (-2873 1200);
PAINT GREEN (-2873 1200);
DISPLAY INVISIBLE (-2873 1200);
FORCEPROP 1 LAST HDL_TAP TRUE
J 2
(-3200 1075);
DISPLAY 1.595745 (-3200 1075);
PAINT GREEN (-3200 1075);
DISPLAY INVISIBLE (-3200 1075);
FORCEPROP 1 LAST BODY_TYPE PLUMBING
J 2
(-2875 1150);
DISPLAY 1.595745 (-2875 1150);
PAINT GREEN (-2875 1150);
DISPLAY INVISIBLE (-2875 1150);
FORCEPROP 2 LAST CDS_LIB mstr_standard
J 0
(-2875 1200);
PAINT MONO (-2875 1200);
DISPLAY INVISIBLE (-2875 1200);
FORCEADD TAP..6
R 2
(-2875 1250);
FORCEPROP 3 LASTPIN (-2925 1250) SIG_NAME M_M_CS_N<6>
J 0
(-2915 1260);
DISPLAY 0.659574 (-2915 1260);
PAINT MONO (-2915 1260);
DISPLAY INVISIBLE (-2915 1260);
FORCEPROP 1 LASTPIN (-2925 1250) BN 6
J 2
(-2873 1258);
DISPLAY 0.617021 (-2873 1258);
PAINT GREEN (-2873 1258);
FORCEPROP 1 LAST PATH I97
J 2
(-2873 1250);
DISPLAY 0.872340 (-2873 1250);
PAINT GREEN (-2873 1250);
DISPLAY INVISIBLE (-2873 1250);
FORCEPROP 1 LAST HDL_TAP TRUE
J 2
(-3200 1125);
DISPLAY 1.595745 (-3200 1125);
PAINT GREEN (-3200 1125);
DISPLAY INVISIBLE (-3200 1125);
FORCEPROP 1 LAST BODY_TYPE PLUMBING
J 2
(-2875 1200);
DISPLAY 1.595745 (-2875 1200);
PAINT GREEN (-2875 1200);
DISPLAY INVISIBLE (-2875 1200);
FORCEPROP 2 LAST CDS_LIB mstr_standard
J 0
(-2875 1250);
PAINT MONO (-2875 1250);
DISPLAY INVISIBLE (-2875 1250);
FORCEADD TAP..6
R 2
(-2875 1300);
FORCEPROP 3 LASTPIN (-2925 1300) SIG_NAME M_M_CS_N<7>
J 0
(-2915 1310);
DISPLAY 0.659574 (-2915 1310);
PAINT MONO (-2915 1310);
DISPLAY INVISIBLE (-2915 1310);
FORCEPROP 1 LASTPIN (-2925 1300) BN 7
J 2
(-2873 1308);
DISPLAY 0.617021 (-2873 1308);
PAINT GREEN (-2873 1308);
FORCEPROP 1 LAST PATH I98
J 2
(-2873 1300);
DISPLAY 0.872340 (-2873 1300);
PAINT GREEN (-2873 1300);
DISPLAY INVISIBLE (-2873 1300);
FORCEPROP 1 LAST HDL_TAP TRUE
J 2
(-3200 1175);
DISPLAY 1.595745 (-3200 1175);
PAINT GREEN (-3200 1175);
DISPLAY INVISIBLE (-3200 1175);
FORCEPROP 1 LAST BODY_TYPE PLUMBING
J 2
(-2875 1250);
DISPLAY 1.595745 (-2875 1250);
PAINT GREEN (-2875 1250);
DISPLAY INVISIBLE (-2875 1250);
FORCEPROP 2 LAST CDS_LIB mstr_standard
J 0
(-2875 1300);
PAINT MONO (-2875 1300);
DISPLAY INVISIBLE (-2875 1300);
FORCEADD TAP..6
R 2
(-2875 1400);
FORCEPROP 3 LASTPIN (-2925 1400) SIG_NAME M_M_ODT<0>
J 0
(-2915 1410);
DISPLAY 0.659574 (-2915 1410);
PAINT MONO (-2915 1410);
DISPLAY INVISIBLE (-2915 1410);
FORCEPROP 1 LASTPIN (-2925 1400) BN 0
J 2
(-2873 1408);
DISPLAY 0.617021 (-2873 1408);
PAINT GREEN (-2873 1408);
FORCEPROP 1 LAST PATH I99
J 2
(-2873 1400);
DISPLAY 0.872340 (-2873 1400);
PAINT GREEN (-2873 1400);
DISPLAY INVISIBLE (-2873 1400);
FORCEPROP 1 LAST HDL_TAP TRUE
J 2
(-3200 1275);
DISPLAY 1.595745 (-3200 1275);
PAINT GREEN (-3200 1275);
DISPLAY INVISIBLE (-3200 1275);
FORCEPROP 1 LAST BODY_TYPE PLUMBING
J 2
(-2875 1350);
DISPLAY 1.595745 (-2875 1350);
PAINT GREEN (-2875 1350);
DISPLAY INVISIBLE (-2875 1350);
FORCEPROP 2 LAST CDS_LIB mstr_standard
J 0
(-2875 1400);
PAINT MONO (-2875 1400);
DISPLAY INVISIBLE (-2875 1400);
FORCEADD INTEL_CORP_BPAGE..1
(0 0);
FORCEPROP 1 LAST CDS_CON_LAST_MODIFIED Fri Jun 16 17:48:24 2017
J 0
(-1425 325);
DISPLAY 1.340426 (-1425 325);
PAINT GREEN (-1425 325);
DISPLAY INVISIBLE (-1425 325);
FORCEPROP 1 LAST CUSTOM_TXT_CDS <CURRENT_DESIGN_SHEET> OF <TOTAL_DESIGN_SHEETS>
J 0
(-500 25);
PAINT ORANGE (-500 25);
FORCEPROP 1 LAST CUSTOM_TXT_CDS <CON_LAST_MODIFIED>
J 0
(-4000 100);
PAINT ORANGE (-4000 100);
FORCEPROP 2 LAST CUSTOM_TXT_CDS <XR_PAGE_TITLE>
J 0
(-7890 5250);
DISPLAY 0.638298 (-7890 5250);
PAINT PINK (-7890 5250);
DISPLAY INVISIBLE (-7890 5250);
FORCEPROP 1 LAST SCH_TITLE SKYLAKE - SKT1 - 8 OF 21
J 0
(-7950 50);
DISPLAY 1.212766 (-7950 50);
PAINT GREEN (-7950 50);
FORCEPROP 1 LAST COMMENT_BODY TRUE
J 0
(12 12);
DISPLAY 0.638298 (12 12);
PAINT GREEN (12 12);
DISPLAY INVISIBLE (12 12);
FORCEPROP 2 LAST CDS_LIB mstr_symbols
J 0
(0 0);
PAINT ORANGE (0 0);
DISPLAY INVISIBLE (0 0);
FORCEPROP 2 LAST PAGE_BORDER TRUE
J 0
(-7890 5250);
DISPLAY 0.851064 (-7890 5250);
PAINT PINK (-7890 5250);
DISPLAY INVISIBLE (-7890 5250);
FORCEPROP 2 LAST CDS_XR_PAGE_TITLE CR-62 : @BASEBOARD_FAB2_LIB.BASEBOARD_FAB2(SCH_1):PAGE62
J 0
(-7890 5250);
DISPLAY 0.638298 (-7890 5250);
PAINT PINK (-7890 5250);
DISPLAY INVISIBLE (-7890 5250);
FORCEADD PRELIM..10
(-4240 2540);
PAINT GRAY (-4240 2540);
FORCEPROP 1 LAST COMMENT_BODY TRUE
J 0
(-4240 2540);
PAINT ORANGE (-4240 2540);
DISPLAY INVISIBLE (-4240 2540);
FORCEPROP 2 LAST CDS_LIB mstr_misc
J 0
(-4240 2540);
PAINT ORANGE (-4240 2540);
DISPLAY INVISIBLE (-4240 2540);
FORCEADD DESIGN_NOTE..1
(-6400 325);
FORCEPROP 0 LAST L1 CPU SYMBOLS 1-30 ARE PRELIMINARY AND SUBJECT TO CHANGE
J 0
(-6600 200);
DISPLAY 1.021277 (-6600 200);
PAINT ORANGE (-6600 200);
FORCEPROP 1 LAST COMMENT_BODY TRUE
J 0
(-6375 425);
DISPLAY 0.978723 (-6375 425);
PAINT ORANGE (-6375 425);
DISPLAY INVISIBLE (-6375 425);
FORCEPROP 2 LAST CDS_LIB mstr_symbols
J 0
(-6400 325);
PAINT ORANGE (-6400 325);
DISPLAY INVISIBLE (-6400 325);
WIRE 17 -1 (-2075 4725)(-2825 4725);
FORCEPROP 2 LAST SIG_NAME M_M_DQS_DP<17:0>
J 0
(-2725 4735);
DISPLAY 0.617021 (-2725 4735);
PAINT ORANGE (-2725 4735);
WIRE 17 -1 (-2825 4675)(-2825 4725);
WIRE 17 -1 (-2825 3825)(-2825 3875);
WIRE 17 -1 (-2825 4625)(-2825 4675);
WIRE 17 -1 (-2825 4575)(-2825 4625);
WIRE 17 -1 (-2825 3875)(-2825 3925);
WIRE 17 -1 (-2825 3925)(-2825 3975);
WIRE 17 -1 (-2825 4525)(-2825 4575);
WIRE 17 -1 (-2825 4475)(-2825 4525);
WIRE 17 -1 (-2825 3975)(-2825 4025);
WIRE 17 -1 (-2825 4025)(-2825 4075);
WIRE 17 -1 (-2825 4425)(-2825 4475);
WIRE 17 -1 (-2825 4375)(-2825 4425);
WIRE 17 -1 (-2825 4075)(-2825 4125);
WIRE 17 -1 (-2825 4125)(-2825 4175);
WIRE 17 -1 (-2825 4325)(-2825 4375);
WIRE 17 -1 (-2825 4275)(-2825 4325);
WIRE 17 -1 (-2825 4175)(-2825 4225);
WIRE 17 -1 (-2825 4225)(-2825 4275);
WIRE 17 -1 (-5650 4775)(-6400 4775);
FORCEPROP 2 LAST SIG_NAME M_M_DQ<63:0>
J 0
(-6350 4785);
DISPLAY 0.617021 (-6350 4785);
PAINT ORANGE (-6350 4785);
WIRE 17 -1 (-5650 4675)(-5650 4775);
WIRE 17 -1 (-5650 4625)(-5650 4675);
WIRE 17 -1 (-5650 4575)(-5650 4625);
WIRE 17 -1 (-5650 4525)(-5650 4575);
WIRE 17 -1 (-5650 4475)(-5650 4525);
WIRE 17 -1 (-5650 4425)(-5650 4475);
WIRE 17 -1 (-5650 4375)(-5650 4425);
WIRE 17 -1 (-5650 4325)(-5650 4375);
WIRE 17 -1 (-5650 4275)(-5650 4325);
WIRE 17 -1 (-5650 4225)(-5650 4275);
WIRE 17 -1 (-5650 4175)(-5650 4225);
WIRE 17 -1 (-5650 4125)(-5650 4175);
WIRE 17 -1 (-5650 4075)(-5650 4125);
WIRE 17 -1 (-5650 4025)(-5650 4075);
WIRE 17 -1 (-5650 3975)(-5650 4025);
WIRE 17 -1 (-5650 3925)(-5650 3975);
WIRE 17 -1 (-5650 3875)(-5650 3925);
WIRE 17 -1 (-5650 3825)(-5650 3875);
WIRE 17 -1 (-5650 3775)(-5650 3825);
WIRE 17 -1 (-5650 3725)(-5650 3775);
WIRE 17 -1 (-5650 3675)(-5650 3725);
WIRE 17 -1 (-5650 3625)(-5650 3675);
WIRE 17 -1 (-5650 3575)(-5650 3625);
WIRE 17 -1 (-5650 3525)(-5650 3575);
WIRE 17 -1 (-5650 3475)(-5650 3525);
WIRE 17 -1 (-5650 3425)(-5650 3475);
WIRE 17 -1 (-5650 3375)(-5650 3425);
WIRE 17 -1 (-5650 3325)(-5650 3375);
WIRE 17 -1 (-5650 3275)(-5650 3325);
WIRE 17 -1 (-5650 3225)(-5650 3275);
WIRE 17 -1 (-5650 3175)(-5650 3225);
WIRE 17 -1 (-5650 3125)(-5650 3175);
WIRE 17 -1 (-5650 3075)(-5650 3125);
WIRE 17 -1 (-5650 3025)(-5650 3075);
WIRE 17 -1 (-5650 2975)(-5650 3025);
WIRE 17 -1 (-5650 2925)(-5650 2975);
WIRE 17 -1 (-5650 2875)(-5650 2925);
WIRE 17 -1 (-5650 2825)(-5650 2875);
WIRE 17 -1 (-5650 2775)(-5650 2825);
WIRE 17 -1 (-5650 2725)(-5650 2775);
WIRE 17 -1 (-5650 2675)(-5650 2725);
WIRE 17 -1 (-5650 2625)(-5650 2675);
WIRE 17 -1 (-5650 2575)(-5650 2625);
WIRE 17 -1 (-5650 2525)(-5650 2575);
WIRE 17 -1 (-5650 2475)(-5650 2525);
WIRE 17 -1 (-5650 2425)(-5650 2475);
WIRE 17 -1 (-5650 2375)(-5650 2425);
WIRE 17 -1 (-5650 2325)(-5650 2375);
WIRE 17 -1 (-5650 2275)(-5650 2325);
WIRE 17 -1 (-5650 2225)(-5650 2275);
WIRE 17 -1 (-5650 2175)(-5650 2225);
WIRE 17 -1 (-5650 2125)(-5650 2175);
WIRE 17 -1 (-5650 2075)(-5650 2125);
WIRE 17 -1 (-5650 2025)(-5650 2075);
WIRE 17 -1 (-5650 1975)(-5650 2025);
WIRE 17 -1 (-5650 1925)(-5650 1975);
WIRE 17 -1 (-5650 1875)(-5650 1925);
WIRE 17 -1 (-5650 1825)(-5650 1875);
WIRE 17 -1 (-5650 1775)(-5650 1825);
WIRE 17 -1 (-5650 1725)(-5650 1775);
WIRE 17 -1 (-5650 1675)(-5650 1725);
WIRE 17 -1 (-5650 1625)(-5650 1675);
WIRE 17 -1 (-5650 1525)(-5650 1575);
WIRE 17 -1 (-5650 1575)(-5650 1625);
WIRE 17 -1 (-2075 3750)(-2825 3750);
FORCEPROP 2 LAST SIG_NAME M_M_DQS_DN<17:0>
J 0
(-2725 3760);
DISPLAY 0.617021 (-2725 3760);
PAINT ORANGE (-2725 3760);
WIRE 17 -1 (-2825 3725)(-2825 3750);
WIRE 17 -1 (-2825 3675)(-2825 3725);
WIRE 17 -1 (-2825 3625)(-2825 3675);
WIRE 17 -1 (-2825 3575)(-2825 3625);
WIRE 17 -1 (-2825 3525)(-2825 3575);
WIRE 17 -1 (-2825 3475)(-2825 3525);
WIRE 17 -1 (-2825 3425)(-2825 3475);
WIRE 17 -1 (-2825 3375)(-2825 3425);
WIRE 17 -1 (-2825 3325)(-2825 3375);
WIRE 17 -1 (-2825 2875)(-2825 2925);
WIRE 17 -1 (-2825 3275)(-2825 3325);
WIRE 17 -1 (-2825 3225)(-2825 3275);
WIRE 17 -1 (-2825 2925)(-2825 2975);
WIRE 17 -1 (-2825 2975)(-2825 3025);
WIRE 17 -1 (-2825 3175)(-2825 3225);
WIRE 17 -1 (-2825 3125)(-2825 3175);
WIRE 17 -1 (-2825 3025)(-2825 3075);
WIRE 17 -1 (-2825 3075)(-2825 3125);
WIRE 17 -1 (-2075 2800)(-2825 2800);
FORCEPROP 2 LAST SIG_NAME M_M_MA<17:0>
J 0
(-2725 2810);
DISPLAY 0.617021 (-2725 2810);
PAINT ORANGE (-2725 2810);
WIRE 17 -1 (-2825 2775)(-2825 2800);
WIRE 17 -1 (-2825 2725)(-2825 2775);
WIRE 17 -1 (-2825 2675)(-2825 2725);
WIRE 17 -1 (-2825 2625)(-2825 2675);
WIRE 17 -1 (-2825 1925)(-2825 1975);
WIRE 17 -1 (-2825 1975)(-2825 2025);
WIRE 17 -1 (-2825 2575)(-2825 2625);
WIRE 17 -1 (-2825 2525)(-2825 2575);
WIRE 17 -1 (-2825 2025)(-2825 2075);
WIRE 17 -1 (-2825 2075)(-2825 2125);
WIRE 17 -1 (-2825 2475)(-2825 2525);
WIRE 17 -1 (-2825 2425)(-2825 2475);
WIRE 17 -1 (-2825 2125)(-2825 2175);
WIRE 17 -1 (-2825 2175)(-2825 2225);
WIRE 17 -1 (-2825 2375)(-2825 2425);
WIRE 17 -1 (-2825 2325)(-2825 2375);
WIRE 17 -1 (-2825 2225)(-2825 2275);
WIRE 17 -1 (-2825 2275)(-2825 2325);
WIRE 17 -1 (-5650 1450)(-6400 1450);
FORCEPROP 2 LAST SIG_NAME M_M_ECC<7:0>
J 0
(-6350 1460);
DISPLAY 0.617021 (-6350 1460);
PAINT ORANGE (-6350 1460);
WIRE 17 -1 (-5650 1425)(-5650 1450);
WIRE 17 -1 (-5650 1375)(-5650 1425);
WIRE 17 -1 (-5650 1325)(-5650 1375);
WIRE 17 -1 (-5650 1275)(-5650 1325);
WIRE 17 -1 (-5650 1225)(-5650 1275);
WIRE 17 -1 (-5650 1175)(-5650 1225);
WIRE 17 -1 (-5650 1125)(-5650 1175);
WIRE 17 -1 (-5650 1075)(-5650 1125);
WIRE 17 -1 (-5650 1000)(-6400 1000);
FORCEPROP 2 LAST SIG_NAME M_M_CLK_DP<3:0>
J 0
(-6350 1010);
DISPLAY 0.617021 (-6350 1010);
PAINT ORANGE (-6350 1010);
WIRE 17 -1 (-5650 975)(-5650 1000);
WIRE 17 -1 (-5650 925)(-5650 975);
WIRE 17 -1 (-5650 875)(-5650 925);
WIRE 17 -1 (-5650 825)(-5650 875);
WIRE 17 -1 (-5650 800)(-6400 800);
FORCEPROP 2 LAST SIG_NAME M_M_CLK_DN<3:0>
J 0
(-6350 810);
DISPLAY 0.617021 (-6350 810);
PAINT ORANGE (-6350 810);
WIRE 17 -1 (-5650 775)(-5650 800);
WIRE 17 -1 (-5650 725)(-5650 775);
WIRE 17 -1 (-5650 675)(-5650 725);
WIRE 17 -1 (-5650 625)(-5650 675);
WIRE 17 -1 (-2075 1600)(-2825 1600);
FORCEPROP 2 LAST SIG_NAME M_M_ODT<3:0>
J 0
(-2725 1610);
DISPLAY 0.617021 (-2725 1610);
PAINT ORANGE (-2725 1610);
WIRE 17 -1 (-2825 1575)(-2825 1600);
WIRE 17 -1 (-2825 1525)(-2825 1575);
WIRE 17 -1 (-2825 1475)(-2825 1525);
WIRE 17 -1 (-2825 1425)(-2825 1475);
WIRE 17 -1 (-2075 1350)(-2825 1350);
FORCEPROP 2 LAST SIG_NAME M_M_CS_N<7:0>
J 0
(-2725 1360);
DISPLAY 0.617021 (-2725 1360);
PAINT ORANGE (-2725 1360);
WIRE 17 -1 (-2825 1325)(-2825 1350);
WIRE 17 -1 (-2825 1275)(-2825 1325);
WIRE 17 -1 (-2825 1225)(-2825 1275);
WIRE 17 -1 (-2825 1175)(-2825 1225);
WIRE 17 -1 (-2825 1125)(-2825 1175);
WIRE 17 -1 (-2825 1075)(-2825 1125);
WIRE 17 -1 (-2825 1025)(-2825 1075);
WIRE 17 -1 (-2825 975)(-2825 1025);
WIRE 17 -1 (-2075 1850)(-2825 1850);
FORCEPROP 2 LAST SIG_NAME M_M_CKE<3:0>
J 0
(-2725 1860);
DISPLAY 0.617021 (-2725 1860);
PAINT ORANGE (-2725 1860);
WIRE 17 -1 (-2825 1825)(-2825 1850);
WIRE 17 -1 (-2825 1775)(-2825 1825);
WIRE 17 -1 (-2825 1725)(-2825 1775);
WIRE 17 -1 (-2825 1675)(-2825 1725);
WIRE 17 -1 (-2075 900)(-2825 900);
FORCEPROP 2 LAST SIG_NAME M_M_BG<1:0>
J 0
(-2725 910);
DISPLAY 0.617021 (-2725 910);
PAINT ORANGE (-2725 910);
WIRE 17 -1 (-2825 875)(-2825 900);
WIRE 17 -1 (-2825 825)(-2825 875);
WIRE 17 -1 (-2075 800)(-2825 800);
FORCEPROP 2 LAST SIG_NAME M_M_BA<1:0>
J 0
(-2725 810);
DISPLAY 0.617021 (-2725 810);
PAINT ORANGE (-2725 810);
WIRE 17 -1 (-2825 775)(-2825 800);
WIRE 17 -1 (-2825 725)(-2825 775);
WIRE 16 -1 (-5050 4250)(-5550 4250);
WIRE 16 -1 (-5550 3550)(-5050 3550);
WIRE 16 -1 (-5050 4150)(-5550 4150);
WIRE 16 -1 (-3350 1550)(-2925 1550);
WIRE 16 -1 (-5550 3250)(-5050 3250);
WIRE 16 -1 (-5550 3400)(-5050 3400);
WIRE 16 -1 (-3350 4100)(-2925 4100);
WIRE 16 -1 (-3350 4050)(-2925 4050);
WIRE 16 -1 (-3350 4650)(-2925 4650);
WIRE 16 -1 (-3350 4600)(-2925 4600);
WIRE 16 -1 (-3350 4550)(-2925 4550);
WIRE 16 -1 (-3350 4250)(-2925 4250);
WIRE 16 -1 (-3350 3550)(-2925 3550);
WIRE 16 -1 (-3350 3500)(-2925 3500);
WIRE 16 -1 (-3350 3450)(-2925 3450);
WIRE 16 -1 (-3350 3400)(-2925 3400);
WIRE 16 -1 (-3350 3350)(-2925 3350);
WIRE 16 -1 (-2925 3300)(-3350 3300);
WIRE 16 -1 (-2925 3250)(-3350 3250);
WIRE 16 -1 (-2925 3200)(-3350 3200);
WIRE 16 -1 (-2925 3150)(-3350 3150);
WIRE 16 -1 (-2925 3000)(-3350 3000);
WIRE 16 -1 (-3350 2850)(-2925 2850);
WIRE 16 -1 (-3350 3950)(-2925 3950);
WIRE 16 -1 (-3350 3900)(-2925 3900);
WIRE 16 -1 (-2925 2750)(-3350 2750);
WIRE 16 -1 (-3350 2700)(-2925 2700);
WIRE 16 -1 (-2925 2650)(-3350 2650);
WIRE 16 -1 (-2925 2600)(-3350 2600);
WIRE 16 -1 (-2925 2550)(-3350 2550);
WIRE 16 -1 (-2925 2500)(-3350 2500);
WIRE 16 -1 (-3350 2450)(-2925 2450);
WIRE 16 -1 (-2925 2400)(-3350 2400);
WIRE 16 -1 (-2925 2350)(-3350 2350);
WIRE 16 -1 (-3350 2300)(-2925 2300);
WIRE 16 -1 (-3350 2050)(-2925 2050);
WIRE 16 -1 (-2075 550)(-3350 550);
FORCEPROP 2 LAST SIG_NAME M_M_ALERT_N
J 0
(-2725 560);
DISPLAY 0.617021 (-2725 560);
PAINT ORANGE (-2725 560);
WIRE 16 -1 (-2075 600)(-3350 600);
FORCEPROP 2 LAST SIG_NAME M_M_ACT_N
J 0
(-2725 610);
DISPLAY 0.617021 (-2725 610);
PAINT ORANGE (-2725 610);
WIRE 16 -1 (-2075 500)(-3350 500);
FORCEPROP 2 LAST SIG_NAME M_M_PAR
J 0
(-2725 510);
DISPLAY 0.617021 (-2725 510);
PAINT ORANGE (-2725 510);
WIRE 16 -1 (-3350 750)(-2925 750);
WIRE 16 -1 (-3350 700)(-2925 700);
WIRE 16 -1 (-3350 850)(-2925 850);
WIRE 16 -1 (-3350 800)(-2925 800);
WIRE 16 -1 (-3350 1800)(-2925 1800);
WIRE 16 -1 (-3350 1750)(-2925 1750);
WIRE 16 -1 (-3350 1700)(-2925 1700);
WIRE 16 -1 (-3350 1650)(-2925 1650);
WIRE 16 -1 (-3350 1300)(-2925 1300);
WIRE 16 -1 (-3350 1250)(-2925 1250);
WIRE 16 -1 (-3350 1200)(-2925 1200);
WIRE 16 -1 (-3350 1150)(-2925 1150);
WIRE 16 -1 (-3350 1100)(-2925 1100);
WIRE 16 -1 (-3350 1050)(-2925 1050);
WIRE 16 -1 (-3350 1000)(-2925 1000);
WIRE 16 -1 (-3350 950)(-2925 950);
WIRE 16 -1 (-3350 2000)(-2925 2000);
WIRE 16 -1 (-3350 1950)(-2925 1950);
WIRE 16 -1 (-3350 1900)(-2925 1900);
WIRE 16 -1 (-3350 1500)(-2925 1500);
WIRE 16 -1 (-3350 1450)(-2925 1450);
WIRE 16 -1 (-3350 1400)(-2925 1400);
WIRE 16 -1 (-5050 4650)(-5550 4650);
WIRE 16 -1 (-5050 4600)(-5550 4600);
WIRE 16 -1 (-5050 4550)(-5550 4550);
WIRE 16 -1 (-5050 4500)(-5550 4500);
WIRE 16 -1 (-5050 4450)(-5550 4450);
WIRE 16 -1 (-5050 4400)(-5550 4400);
WIRE 16 -1 (-5050 4350)(-5550 4350);
WIRE 16 -1 (-5050 4300)(-5550 4300);
WIRE 16 -1 (-5050 4200)(-5550 4200);
WIRE 16 -1 (-5050 4100)(-5550 4100);
WIRE 16 -1 (-5050 4050)(-5550 4050);
WIRE 16 -1 (-5050 4000)(-5550 4000);
WIRE 16 -1 (-5050 3950)(-5550 3950);
WIRE 16 -1 (-5050 3900)(-5550 3900);
WIRE 16 -1 (-5050 3850)(-5550 3850);
WIRE 16 -1 (-5050 3800)(-5550 3800);
WIRE 16 -1 (-5050 3750)(-5550 3750);
WIRE 16 -1 (-5050 3700)(-5550 3700);
WIRE 16 -1 (-5050 3650)(-5550 3650);
WIRE 16 -1 (-5550 3600)(-5050 3600);
WIRE 16 -1 (-5050 3500)(-5550 3500);
WIRE 16 -1 (-5550 3450)(-5050 3450);
WIRE 16 -1 (-5050 3350)(-5550 3350);
WIRE 16 -1 (-5550 3300)(-5050 3300);
WIRE 16 -1 (-5550 3200)(-5050 3200);
WIRE 16 -1 (-5550 3150)(-5050 3150);
WIRE 16 -1 (-5550 3100)(-5050 3100);
WIRE 16 -1 (-5550 3050)(-5050 3050);
WIRE 16 -1 (-5550 3000)(-5050 3000);
WIRE 16 -1 (-5550 2950)(-5050 2950);
WIRE 16 -1 (-5550 2900)(-5050 2900);
WIRE 16 -1 (-5550 2850)(-5050 2850);
WIRE 16 -1 (-5550 2800)(-5050 2800);
WIRE 16 -1 (-5550 2750)(-5050 2750);
WIRE 16 -1 (-5550 2700)(-5050 2700);
WIRE 16 -1 (-5550 2650)(-5050 2650);
WIRE 16 -1 (-5550 2600)(-5050 2600);
WIRE 16 -1 (-5550 2550)(-5050 2550);
WIRE 16 -1 (-5550 2500)(-5050 2500);
WIRE 16 -1 (-5550 2450)(-5050 2450);
WIRE 16 -1 (-5550 2400)(-5050 2400);
WIRE 16 -1 (-5550 2350)(-5050 2350);
WIRE 16 -1 (-5550 2300)(-5050 2300);
WIRE 16 -1 (-5550 2250)(-5050 2250);
WIRE 16 -1 (-5550 2200)(-5050 2200);
WIRE 16 -1 (-5550 2150)(-5050 2150);
WIRE 16 -1 (-5550 2100)(-5050 2100);
WIRE 16 -1 (-5550 2050)(-5050 2050);
WIRE 16 -1 (-5050 750)(-5550 750);
WIRE 16 -1 (-5050 700)(-5550 700);
WIRE 16 -1 (-5050 650)(-5550 650);
WIRE 16 -1 (-5050 600)(-5550 600);
WIRE 16 -1 (-5050 950)(-5550 950);
WIRE 16 -1 (-5050 900)(-5550 900);
WIRE 16 -1 (-5050 850)(-5550 850);
WIRE 16 -1 (-5050 800)(-5550 800);
WIRE 16 -1 (-5550 2000)(-5050 2000);
WIRE 16 -1 (-5550 1950)(-5050 1950);
WIRE 16 -1 (-5550 1900)(-5050 1900);
WIRE 16 -1 (-5550 1850)(-5050 1850);
WIRE 16 -1 (-5050 1800)(-5550 1800);
WIRE 16 -1 (-5550 1750)(-5050 1750);
WIRE 16 -1 (-5550 1700)(-5050 1700);
WIRE 16 -1 (-5550 1500)(-5050 1500);
WIRE 16 -1 (-5050 1400)(-5550 1400);
WIRE 16 -1 (-5050 1350)(-5550 1350);
WIRE 16 -1 (-5050 1300)(-5550 1300);
WIRE 16 -1 (-5050 1250)(-5550 1250);
WIRE 16 -1 (-5050 1200)(-5550 1200);
WIRE 16 -1 (-5050 1150)(-5550 1150);
WIRE 16 -1 (-5050 1100)(-5550 1100);
WIRE 16 -1 (-5050 1050)(-5550 1050);
WIRE 16 -1 (-5050 500)(-6400 500);
FORCEPROP 2 LAST SIG_NAME M_M_C<2>
J 0
(-6350 510);
DISPLAY 0.617021 (-6350 510);
PAINT ORANGE (-6350 510);
WIRE 16 -1 (-3350 4300)(-2925 4300);
WIRE 16 -1 (-3350 4350)(-2925 4350);
WIRE 16 -1 (-3350 4400)(-2925 4400);
WIRE 16 -1 (-3350 4450)(-2925 4450);
WIRE 16 -1 (-3350 4500)(-2925 4500);
WIRE 16 -1 (-2925 2100)(-3350 2100);
WIRE 16 -1 (-3350 2150)(-2925 2150);
WIRE 16 -1 (-3350 2200)(-2925 2200);
WIRE 16 -1 (-2925 2250)(-3350 2250);
WIRE 16 -1 (-3350 3700)(-2925 3700);
WIRE 16 -1 (-3350 3800)(-2925 3800);
WIRE 16 -1 (-3350 3850)(-2925 3850);
WIRE 16 -1 (-3350 3650)(-2925 3650);
WIRE 16 -1 (-3350 3600)(-2925 3600);
WIRE 16 -1 (-2925 2900)(-3350 2900);
WIRE 16 -1 (-2925 2950)(-3350 2950);
WIRE 16 -1 (-3350 3100)(-2925 3100);
WIRE 16 -1 (-2925 3050)(-3350 3050);
WIRE 16 -1 (-5050 1650)(-5550 1650);
WIRE 16 -1 (-5550 1600)(-5050 1600);
WIRE 16 -1 (-5550 1550)(-5050 1550);
WIRE 16 -1 (-3350 4000)(-2925 4000);
WIRE 16 -1 (-3350 4150)(-2925 4150);
WIRE 16 -1 (-3350 4200)(-2925 4200);
FORCENOTE
ROOM=CPU1
(-7950 375) 0;
DISPLAY LEFT (-7950 375);
DISPLAY 1.723404 (-7950 375);
PAINT PURPLE (-7950 375);
FORCENOTE
BOM_COST=PROC_SOCKET
(-7950 250) 0;
DISPLAY LEFT (-7950 250);
DISPLAY 1.723404 (-7950 250);
PAINT PURPLE (-7950 250);
QUIT
